P  JOB   F:/<user>/FB/R4006-TIMING/brd/gerber-3/R4006-B0001-02_R01.brd             
P  FORM  F                                                                      
P  CODE  00                                                                     
P  DIM   N                                                                      
P  UNITS CUST 0                                                                 
P  TITLE F:/<user>/FB/R4006-TIMING/brd/gerber-3/R4006-B0001-02_R01.brd             
P  NUM   001                                                                    
P  REV   A                                                                      
C                                                                               
C  IPC-D-356 Ouptut File from Allegro                                           
C  IPC File Date: Fri Feb 25 18:14:55 2022                                      
C                                                                               
C                                                                               
C  Board File:             R4006-B0001-02_R01.brd                               
C  Design Rule Status:     UP TO DATE                                           
C  Unit of Measure:        mils                                                 
C  Decimal Place Accuracy: 2                                                    
C  Number of etch Layers:  10                                                   
C  Board Thickness(mils):  61.800000                                            
C  Drawing Extents(mils):  -4330709  -9842520  4330709  7874016                 
C                                                                               
C                                                                               
C  BOARD LAYER INFORMATION                                                      
C                                                                               
C     Layer      Layer            Layer             Film  Layer                 
C     Name       Material         Type              Type  Number                
C  ---------------------------------------------------------                    
C  TOP           COPPER           CONDUCTOR         POS     1                   
C  L02_GND1      COPPER           PLANE             NEG     2                   
C  L03_SIG1      COPPER           CONDUCTOR         POS     3                   
C  L04_GND2      COPPER           PLANE             NEG     4                   
C  L05_VCC1      COPPER           PLANE             NEG     5                   
C  L06_VCC2      COPPER           PLANE             NEG     6                   
C  L07_GND3      COPPER           PLANE             NEG     7                   
C  L08_SIG2      COPPER           CONDUCTOR         POS     8                   
C  L09_GND4      COPPER           PLANE             NEG     9                   
C  BOTTOM        COPPER           CONDUCTOR         POS    10                   
C                                                                               
C                                                                               
C  PADSTACK INFORMATION                                                         
C                                                                               
C     Padstack          First     Last                                          
C     Name              Layer     Layer     Width     Height                    
C  ---------------------------------------------------------                    
C  V008C018P_ANTI028-NS TOP       BOTTOM         2800      2800                 
C  V010C020P_ANTI026_TP TOP       BOTTOM         3400      3400                 
C  V012C024P_TP030B     TOP       BOTTOM         3400      3400                 
C  V010C020P_ANTI026    TOP       BOTTOM         2600      2600                 
C  V008C018P_ANTI026    TOP       BOTTOM         2600      2600                 
C  V012C024P            TOP       BOTTOM         3400      3400                 
C  S056X088             TOP       TOP            6000      9200                 
C  S056X092             TOP       TOP            6000      9600                 
C  016C024P             TOP       BOTTOM         4200      4200                 
C  024X063OB035X075P    TOP       BOTTOM         5000      8798                 
C  S024X017             TOP       TOP            2800      2100                 
C  S062X014             TOP       TOP            6600      1800                 
C  S020SQ               TOP       TOP            2400      2400                 
C  S012X064             TOP       TOP            1600      6800                 
C  S116X138             TOP       TOP           12000     14200                 
C  V008C018P-ANTI28-NSM TOP       BOTTOM         3000      3000                 
C  TPV010CT020B030      TOP       BOTTOM         3400      3400                 
C  FID040               TOP       TOP           12000     12000                 
C  V008C018P_NATI28_TP0 TOP       BOTTOM         3400      3400                 
C  V008C018P_ANTI026_NS TOP       BOTTOM         2600      2600                 
C  V008C018P-ANTI28-NSM TOP       BOTTOM         2800      2800                 
C  V008C018P_ANTI28     TOP       BOTTOM         2800      2800                 
C  063C090P             TOP       BOTTOM         9400      9400                 
C  S018X020             TOP       TOP            2200      2400                 
C  S033X035             TOP       TOP            3700      3900                 
C  S115SQ-NSM           TOP       TOP           11500     11500                 
C  S012X049             TOP       TOP            1600      5300                 
C  S012X046             TOP       TOP            1600      5000                 
C  S049X012             TOP       TOP            5300      1600                 
C  S046X012             TOP       TOP            5000      1600                 
C  S038X012             TOP       TOP            4200      1600                 
C  V012C024-NTH         TOP       BOTTOM         3300      3300                 
C  MTH125C115N          TOP       BOTTOM        15000     15000                 
C  MTH100C090N          TOP       BOTTOM        12500     12500                 
C  076C104P             TOP       BOTTOM        10800     10800                 
C  076S104P             TOP       BOTTOM        10800     10800                 
C  079C100P             TOP       BOTTOM        10500     10500                 
C  MTH118C108N          TOP       BOTTOM        14300     14300                 
C  059C086P             TOP       BOTTOM         9000      9000                 
C  V010C020P_TP030B     TOP       BOTTOM         3400      3400                 
C  V008C018P_TP030B     TOP       BOTTOM         3400      3400                 
C  V008C018P_ANTI026_TP TOP       BOTTOM         3400      3400                 
C  V008C018P            TOP       BOTTOM         3000      3000                 
C  V010C020P            TOP       BOTTOM         3200      3200                 
C  V010C020P_SM014-NTH  TOP       BOTTOM         3200      3200                 
C  166CT244CB198P       TOP       BOTTOM        24800     24800                 
C  024X051OB071X075P_R  TOP       BOTTOM         7524      7900                 
C  024X051OB071X075P_L  TOP       BOTTOM         7524      7900                 
C  033C057P             TOP       BOTTOM         6100      6100                 
C  S039X071-NSM         TOP       TOP            3900      7100                 
C  S014X011             TOP       TOP            1800      1500                 
C  S011X014             TOP       TOP            1500      1800                 
C  S010X023             TOP       TOP            1400      2700                 
C  S027X010             TOP       TOP            3100      1400                 
C  TP030C_B             BOTTOM    BOTTOM         3400      3400                 
C  S020C_CST_V2         TOP       TOP            2360      2360                 
C  S035X025             TOP       TOP            3900      2900                 
C  S033X017             TOP       TOP            3700      2100                 
C  S071X096-NSM         TOP       TOP            7100      9600                 
C  S033X012             TOP       TOP            3700      1600                 
C  S072X020             TOP       TOP            7600      2400                 
C  S057X071-NSM         TOP       TOP            5700      7100                 
C  SH041X021-L          TOP       TOP            4500      2500                 
C  SH041X021-R          TOP       TOP            4500      2500                 
C  S041X012             TOP       TOP            4500      1600                 
C  S040X088             TOP       TOP            4400      9200                 
C  S010X071             TOP       TOP            1400      7500                 
C  S045X104             TOP       TOP            4900     10800                 
C  S053X008             TOP       TOP            5700      1200                 
C  S008X037             TOP       TOP            1200      4100                 
C  S008X106             TOP       TOP            1200     11000                 
C  S045X012             TOP       TOP            4900      1600                 
C  S045X016             TOP       TOP            4900      2000                 
C  S024X012             TOP       TOP            2800      1600                 
C  S010X024             TOP       TOP            1400      2800                 
C  S020X024             TOP       TOP            2400      2800                 
C  S005X024_V3_NSM      TOP       TOP             500      2400                 
C  S039X055             TOP       TOP            4300      5900                 
C  S063X118             TOP       TOP            6700     12200                 
C  S228X244-NSM         TOP       TOP           22800     24400                 
C  S094X130             TOP       TOP            9800     13400                 
C  S085X108             TOP       TOP            8900     11200                 
C  S020X065             TOP       TOP            2400      6900                 
C  S096X146             TOP       TOP           10000     15000                 
C  S001X001             TOP       TOP             100       100                 
C  SH052X046            TOP       TOP            5638      4962                 
C  S013X044             TOP       TOP            1700      4800                 
C  S049X010-NSM         TOP       TOP            4900      1000                 
C  S047X012             TOP       TOP            5100      1600                 
C  S055X047             TOP       TOP            5900      5100                 
C  S033X055             TOP       TOP            3700      5900                 
C  S013X038             TOP       TOP            1700      4200                 
C  S014X062             TOP       TOP            1800      6600                 
C  S031SQ               TOP       TOP            3500      3500                 
C  S018X060             TOP       TOP            2200      6400                 
C  S050X140             TOP       TOP            5400     14400                 
C  S030X034             TOP       TOP            3400      3800                 
C  S057X039             TOP       TOP            6100      4300                 
C  S057X043             TOP       TOP            6100      4700                 
C  S059X075             TOP       TOP            6300      7900                 
C  S016X053             TOP       TOP            2000      5700                 
C  S039X041             TOP       TOP            4300      4500                 
C  S041X087             TOP       TOP            4500      9100                 
C  EFT028X165           TOP       TOP            3200     16900                 
C  EFB028X165           BOTTOM    BOTTOM         3200     16900                 
C  EFB028X126           BOTTOM    BOTTOM         3200     13000                 
C  EFT028X126           TOP       TOP            3200     13000                 
C  S020X047             TOP       TOP            2400      5100                 
C  S038X054             TOP       TOP            4200      5800                 
C  S025C                TOP       TOP            2900      2900                 
C  S028X024             TOP       TOP            3200      2800                 
C  S012X015             TOP       TOP            1600      1900                 
C                                                                               
C                                                                               
C  ****************************************                                     
C             Tolerance Data                                                    
C  ****************************************                                     
C                                                                               
C                                                                               
C  Overall Printed Board Size                                                   
P  TOL    0 1 000001 000001                                                     
C  Overall Printed Board Thickness                                              
P  TOL    1 1 000010 000010                                                     
C  Overall Layer Thickness                                                      
P  TOL    2 1 000001 000001                                                     
C  Line Width                                                                   
P  TOL    3 1 000001 000001                                                     
C  Land Diameters                                                               
P  TOL    4 1 000001 000001                                                     
C  Finished Hole Diameter                                                       
P  TOL    5 1 000001 000001                                                     
C  Hole Locations                                                               
P  TOL    6 1 000001 000001                                                     
C  Other Features                                                               
P  TOL    7 1 000001 000001                                                     
C  Registration                                                                 
P  TOL    8 1 000001 000001                                                     
C                                                                               
C      Area                                                                     
P  AREA1 X-433071Y-984252X+433071Y+787402                                       
C                                                                               
C  ****************************************                                     
C     Name mapping for long Signal names                                        
C  ****************************************                                     
C                                                                               
C  NNAMEm0000 R_RGB_LED_I2C_SDA                                                 
C  NNAMEm0001 R_RGB_LED_I2C_SCL                                                 
C  NNAMEm0002 UNNAMED_3_RESISTOR_I151_2                                         
C  NNAMEm0003 FPGA_IN_RST_DLY_N                                                 
C  NNAMEm0004 RGB_LED_SHUTDOWN_N                                                
C  NNAMEm0005 UNNAMED_12_CAPACITOR_I332_2                                       
C  NNAMEm0006 UNNAMED_12_CAPACITOR_I328_2                                       
C  NNAMEm0007 UNNAMED_12_CAPACITOR_I321_2                                       
C  NNAMEm0008 UNNAMED_12_CAPACITOR_I318_2                                       
C  NNAMEm0009 UNNAMED_5_24LC16BTISTTSSOP8_I_2                                   
C  NNAMEm0010 UNNAMED_5_24LC16BTISTTSSOP8_I_1                                   
C  NNAMEm0011 UNNAMED_5_24LC16BTISTTSSOP8_I15                                   
C  NNAMEm0012 UNNAMED_525_ISL80101IRAJZDFN10_                                   
C  NNAMEm0013 UNNAMED_525_CAPACITOR_I7_1                                        
C  NNAMEm0014 UNNAMED_525_CAPACITOR_I18_1                                       
C  NNAMEm0015 UNNAMED_525_CAPACITOR_I16_1                                       
C  NNAMEm0016 UNNAMED_525_CAPACITOR_I14_1                                       
C  NNAMEm0017 UNNAMED_524_RESISTOR_I463_2                                       
C  NNAMEm0018 UNNAMED_524_RESISTOR_I432_2                                       
C  NNAMEm0019 UNNAMED_524_POWERMOS3PNCHV1_I44                                   
C  NNAMEm0020 UNNAMED_524_FT4232HLREELQFP64_I                                   
C  NNAMEm0021 UNNAMED_524_FT4232HLREELQFP64_7                                   
C  NNAMEm0022 UNNAMED_524_FT4232HLREELQFP64_6                                   
C  NNAMEm0023 UNNAMED_524_FT4232HLREELQFP64_5                                   
C  NNAMEm0024 UNNAMED_524_FT4232HLREELQFP64_4                                   
C  NNAMEm0025 UNNAMED_524_FT4232HLREELQFP64_3                                   
C  NNAMEm0026 UNNAMED_524_FT4232HLREELQFP64_2                                   
C  NNAMEm0027 UNNAMED_524_FT4232HLREELQFP64_1                                   
C  NNAMEm0028 UNNAMED_524_CONNUSB14PGH4FRAT_1                                   
C  NNAMEm0029 UNNAMED_524_CONNUSB14PGH4FRATH_                                   
C  NNAMEm0030 UNNAMED_524_CAPACITOR_I7_2                                        
C  NNAMEm0031 UNNAMED_524_CAPACITOR_I10_2                                       
C  NNAMEm0032 UNNAMED_16_CONNHDR2X6FSSMT_I1_7                                   
C  NNAMEm0033 UNNAMED_16_CONNHDR2X6FSSMT_I1_6                                   
C  NNAMEm0034 UNNAMED_16_CONNHDR2X6FSSMT_I1_5                                   
C  NNAMEm0035 UNNAMED_16_CONNHDR2X6FSSMT_I1_4                                   
C  NNAMEm0036 UNNAMED_16_CONNHDR2X6FSSMT_I1_3                                   
C  NNAMEm0037 UNNAMED_16_CONNHDR2X6FSSMT_I1_2                                   
C  NNAMEm0038 UNNAMED_16_CONNHDR2X6FSSMT_I1_1                                   
C  NNAMEm0039 UNNAMED_16_CONNHDR2X6FSSMT_I161                                   
C  NNAMEm0040 UNNAMED_14_OPTICAL_I289_A                                         
C  NNAMEm0041 UART_FT4232_TX_FPGA_RX                                            
C  NNAMEm0042 UART_FT4232_RX_FPGA_TX                                            
C  NNAMEm0043 R_FT4232_I2C_SDA_OUT                                              
C  NNAMEm0044 R_FT4232_I2C_SDA_IN                                               
C  NNAMEm0045 R_FT4232_I2C_SCL                                                  
C  NNAMEm0046 R_FT4232_CHD_TX                                                   
C  NNAMEm0047 R_FT4232_CHD_RX                                                   
C  NNAMEm0048 R_FT4232_CHC_TX                                                   
C  NNAMEm0049 R_FT4232_CHC_RX                                                   
C  NNAMEm0050 FT4232_TMS_SPICS_N                                                
C  NNAMEm0051 FT4232_TDO_MISO                                                   
C  NNAMEm0052 FT4232_TDI_MOSI                                                   
C  NNAMEm0053 FT4232_TCK_SCLK                                                   
C  NNAMEm0054 FT4232_SPI_MOSI                                                   
C  NNAMEm0055 FT4232_SPI_MISO                                                   
C  NNAMEm0056 FT4232_SPI_CS_N                                                   
C  NNAMEm0057 FT4232_MUX3_SEL                                                   
C  NNAMEm0058 FT4232_MUX2_SEL                                                   
C  NNAMEm0059 FT4232_MUX1_SEL                                                   
C  NNAMEm0060 FT4232_FPGA_TMS                                                   
C  NNAMEm0061 FT4232_FPGA_TDO                                                   
C  NNAMEm0062 FT4232_FPGA_TDI                                                   
C  NNAMEm0063 FT4232_FPGA_TCK                                                   
C  NNAMEm0064 FPGA_PCA9546_I2C_SDA                                              
C  NNAMEm0065 FPGA_PCA9546_I2C_SCL                                              
C  NNAMEm0066 FPGA_OUT_SN_EEPROM_WP                                             
C  NNAMEm0067 FPGA_OUT_SEC_EEPROM_WP                                            
C  NNAMEm0068 FPGA_OUT_MUX3_SEL                                                 
C  NNAMEm0069 FPGA_OUT_MUX2_SEL                                                 
C  NNAMEm0070 FPGA_OUT_MUX1_SEL                                                 
C  NNAMEm0071 FPGA_IO_FT_USBDET_RST_N                                           
C  NNAMEm0072 FPGA_FLASH_DQ1_MISO                                               
C  NNAMEm0073 FPGA_FLASH_DQ0_MOSI                                               
C  NNAMEm0074 FPGA_FLASH_CS_N                                                   
C  NNAMEm0075 FPGA_EEPROM_I2C_SDA                                               
C  NNAMEm0076 FPGA_EEPROM_I2C_SCL                                               
C  NNAMEm0077 UNNAMED_5_CONNHDR2X2MSSMT_I12_1                                   
C  NNAMEm0078 UNNAMED_5_CONNHDR2X2MSSMT_I126_                                   
C  NNAMEm0079 UNNAMED_14_LED4PV14_I269_4                                        
C  NNAMEm0080 UNNAMED_14_LED4PV14_I269_3                                        
C  NNAMEm0081 UNNAMED_14_LED4PV14_I269_1                                        
C  NNAMEm0082 UNNAMED_14_LED4PV14_I268_4                                        
C  NNAMEm0083 UNNAMED_14_LED4PV14_I268_3                                        
C  NNAMEm0084 UNNAMED_14_LED4PV14_I268_1                                        
C  NNAMEm0085 UNNAMED_14_LED4PV14_I267_4                                        
C  NNAMEm0086 UNNAMED_14_LED4PV14_I267_3                                        
C  NNAMEm0087 UNNAMED_14_LED4PV14_I267_1                                        
C  NNAMEm0088 UNNAMED_14_LED4PV14_I266_4                                        
C  NNAMEm0089 UNNAMED_14_LED4PV14_I266_3                                        
C  NNAMEm0090 UNNAMED_14_LED4PV14_I266_1                                        
C  NNAMEm0091 UNNAMED_14_LED4PV14_I265_4                                        
C  NNAMEm0092 UNNAMED_14_LED4PV14_I265_3                                        
C  NNAMEm0093 UNNAMED_14_LED4PV14_I265_1                                        
C  NNAMEm0094 UNNAMED_8_PCA9508DPTSSOP8_I51_E                                   
C  NNAMEm0095 UNNAMED_14_IS32FL3207QWLA3TRQ_1                                   
C  NNAMEm0096 UNNAMED_14_IS32FL3207QWLA3TRQFN                                   
C  NNAMEm0097 RGB_LED_I2C_SDA                                                   
C  NNAMEm0098 RGB_LED_I2C_SCL                                                   
C  NNAMEm0099 FPGA_OUT_RGB_LED_SHUTDOWN_N                                       
C  NNAMEm0100 FPGA_M_RGB_LED_I2C_SDA                                            
C  NNAMEm0101 FPGA_M_RGB_LED_I2C_SCL                                            
C  NNAMEm0102 BF_ICP10100_I2C_SDA                                               
C  NNAMEm0103 BF_ICP10100_I2C_SCL                                               
C  NNAMEm0104 UNNAMED_14_OPTICAL_I194_A                                         
C  NNAMEm0105 UNNAMED_14_OPTICAL_I191_A                                         
C  NNAMEm0106 FPGA_OUT_SMA4_LED_RED_N                                           
C  NNAMEm0107 FPGA_OUT_SMA4_LED_GREEN_N                                         
C  NNAMEm0108 FPGA_OUT_SMA4_LED_BLUE_N                                          
C  NNAMEm0109 FPGA_OUT_SMA3_LED_RED_N                                           
C  NNAMEm0110 FPGA_OUT_SMA3_LED_GREEN_N                                         
C  NNAMEm0111 FPGA_OUT_SMA3_LED_BLUE_N                                          
C  NNAMEm0112 FPGA_OUT_SMA2_LED_RED_N                                           
C  NNAMEm0113 FPGA_OUT_SMA2_LED_GREEN_N                                         
C  NNAMEm0114 FPGA_OUT_SMA2_LED_BLUE_N                                          
C  NNAMEm0115 FPGA_OUT_SMA1_LED_RED_N                                           
C  NNAMEm0116 FPGA_OUT_SMA1_LED_GREEN_N                                         
C  NNAMEm0117 FPGA_OUT_SMA1_LED_BLUE_N                                          
C  NNAMEm0118 FPGA_OUT_GPS_LED_RED_N                                            
C  NNAMEm0119 FPGA_OUT_GPS_LED_GREEN_N                                          
C  NNAMEm0120 FPGA_OUT_GPS_LED_BLUE_N                                           
C  NNAMEm0121 UNNAMED_12_74HCT2G125DPTSSOP8_9                                   
C  NNAMEm0122 UNNAMED_12_74HCT2G125DPTSSOP8_6                                   
C  NNAMEm0123 SMA2_SIG_IO_CONN                                                  
C  NNAMEm0124 SMA1_SIG_IO_CONN                                                  
C  NNAMEm0125 SMA4_SIG_IO_CONN                                                  
C  NNAMEm0126 SMA3_SIG_IO_CONN                                                  
C  NNAMEm0127 BF_SMA2_SIG_IO_CONN                                               
C  NNAMEm0128 BF_SMA1_SIG_IO_CONN                                               
C  NNAMEm0129 BF_SMA4_SIG_IO_CONN                                               
C  NNAMEm0130 BF_SMA3_SIG_IO_CONN                                               
C  NNAMEm0131 UNNAMED_6_LM75BDPTSSOP8_I81_A2                                    
C  NNAMEm0132 UNNAMED_6_LM75BDPTSSOP8_I81_A1                                    
C  NNAMEm0133 UNNAMED_6_LM75BDPTSSOP8_I81_A0                                    
C  NNAMEm0134 UNNAMED_6_LM75BDPTSSOP8_I59_A2                                    
C  NNAMEm0135 UNNAMED_6_LM75BDPTSSOP8_I59_A1                                    
C  NNAMEm0136 UNNAMED_6_LM75BDPTSSOP8_I59_A0                                    
C  NNAMEm0137 UNNAMED_527_POWERMOS3PNCHV1_I23                                   
C  NNAMEm0138 UNNAMED_527_FUSE_I244_1                                           
C  NNAMEm0139 R_LM75B_3_I2C_SDA                                                 
C  NNAMEm0140 R_LM75B_2_I2C_SDA                                                 
C  NNAMEm0141 FPGA_IN_LM75B_INT3_N                                              
C  NNAMEm0142 FPGA_IN_LM75B_INT2_N                                              
C  NNAMEm0143 FPGA_IN_LM75B_INT1_N                                              
C  NNAMEm0144 DBG_UART_MAC_TX                                                   
C  NNAMEm0145 DBG_UART_MAC_RX                                                   
C  NNAMEm0146 DBG_UART_GPS_TXD                                                  
C  NNAMEm0147 DBG_UART_GPS_RXD                                                  
C  NNAMEm0148 UNNAMED_14_OPTICAL_I138_A                                         
C  NNAMEm0149 SMA4_SIG_OUT_BF_EN_N                                              
C  NNAMEm0150 SMA4_SIG_IN_BF_EN_N                                               
C  NNAMEm0151 SMA4_LED_GREEN_N                                                  
C  NNAMEm0152 SMA4_LED_BLUE_N                                                   
C  NNAMEm0153 SMA3_SIG_OUT_BF_EN_N                                              
C  NNAMEm0154 SMA3_SIG_IN_BF_EN_N                                               
C  NNAMEm0155 SMA3_LED_GREEN_N                                                  
C  NNAMEm0156 SMA3_LED_BLUE_N                                                   
C  NNAMEm0157 SMA2_SIG_OUT_BF_EN_N                                              
C  NNAMEm0158 SMA2_SIG_IN_BF_EN_N                                               
C  NNAMEm0159 SMA2_LED_GREEN_N                                                  
C  NNAMEm0160 SMA2_LED_BLUE_N                                                   
C  NNAMEm0161 SMA1_SIG_OUT_BF_EN_N                                              
C  NNAMEm0162 SMA1_SIG_IN_BF_EN_N                                               
C  NNAMEm0163 SMA1_LED_GREEN_N                                                  
C  NNAMEm0164 SMA1_LED_BLUE_N                                                   
C  NNAMEm0165 GPS_SMA_LED_RED_N                                                 
C  NNAMEm0166 GPS_SMA_LED_GREEN_N                                               
C  NNAMEm0167 GPS_SMA_LED_BLUE_N                                                
C  NNAMEm0168 XP1R8V_ICP10100                                                   
C  NNAMEm0169 UNNAMED_9_BNO080LGA28_I29_XOUT3                                   
C  NNAMEm0170 UNNAMED_9_BNO080LGA28_I29_PS1                                     
C  NNAMEm0171 UNNAMED_9_BNO080LGA28_I29_PS0                                     
C  NNAMEm0172 UNNAMED_9_BNO080LGA28_I29_HCS                                     
C  NNAMEm0173 UNNAMED_9_BNO080LGA28_I29_CLKSE                                   
C  NNAMEm0174 UNNAMED_9_BNO080LGA28_I29_CAP                                     
C  NNAMEm0175 UNNAMED_8_ICP10100LGA10_I24_R_4                                   
C  NNAMEm0176 UNNAMED_8_ICP10100LGA10_I24_R_3                                   
C  NNAMEm0177 UNNAMED_8_ICP10100LGA10_I24_R_2                                   
C  NNAMEm0178 UNNAMED_8_ICP10100LGA10_I24_R_1                                   
C  NNAMEm0179 UNNAMED_8_ICP10100LGA10_I24_RES                                   
C  NNAMEm0180 UNNAMED_515_NCP45560IMNTWGHDFN1                                   
C  NNAMEm0181 UNNAMED_14_OPTICAL_I139_A                                         
C  NNAMEm0182 UNNAMED_527_RESISTOR_I206_1                                       
C  NNAMEm0183 SMA_ANALOG_TUNING_IN                                              
C  NNAMEm0184 R_SHT3X_ALERT_N                                                   
C  NNAMEm0185 R_BNO080_I2C_SDA                                                  
C  NNAMEm0186 R_BNO080_I2C_SCL                                                  
C  NNAMEm0187 RSVD_DBG_USB_MUX_SEL                                              
C  NNAMEm0188 FPGA_OUT_SHT3X_RST_N                                              
C  NNAMEm0189 FPGA_OUT_PCA9546_RST_N                                            
C  NNAMEm0190 FPGA_OUT_I2C_BUFFER_EN                                            
C  NNAMEm0191 FPGA_OUT_BNO080_RST_N                                             
C  NNAMEm0192 FPGA_OUT_BNO080_BOOT_N                                            
C  NNAMEm0193 FPGA_IN_SHT3X_ALERT_N                                             
C  NNAMEm0194 FPGA_IN_MAC_USB_OC_N                                              
C  NNAMEm0195 FPGA_IN_MAC_BITEOUT                                               
C  NNAMEm0196 FPGA_IN_MAC_ALARM_OUT_N                                           
C  NNAMEm0197 FPGA_IN_MAC_10MHZ_OUT                                             
C  NNAMEm0198 FPGA_IN_GPSTP2_OUT                                                
C  NNAMEm0199 FPGA_IN_GPSTP1_OUT                                                
C  NNAMEm0200 FPGA_IN_BNO080_INT_N                                              
C  NNAMEm0201 FPGA_CFG_INIT_N                                                   
C  NNAMEm0202 CONN_MICRO_USB_DP                                                 
C  NNAMEm0203 CONN_MICRO_USB_DM                                                 
C  NNAMEm0204 R_BNO080_EVN_SDA                                                  
C  NNAMEm0205 R_BNO080_EVN_SCL                                                  
C  NNAMEm0206 XP3R3V_FPGA_EN_R                                                  
C  NNAMEm0207 XP1R8V_FPGA_VCCAUX                                                
C  NNAMEm0208 XP1R0V_FPGA_VCCINT                                                
C  NNAMEm0209 XP1R0V_FPGA_MGTAVCC                                               
C  NNAMEm0210 XP1R0V_FB_R_TO_AGND                                               
C  NNAMEm0211 UNNAMED_523_CAPACITOR_I9_1                                        
C  NNAMEm0212 UNNAMED_523_CAPACITOR_I7_1                                        
C  NNAMEm0213 UNNAMED_523_CAPACITOR_I31_2                                       
C  NNAMEm0214 UNNAMED_523_CAPACITOR_I28_1                                       
C  NNAMEm0215 UNNAMED_523_CAPACITOR_I24_1                                       
C  NNAMEm0216 VDD3V3_OSC_125M                                                   
C  NNAMEm0217 VDD3V3_OSC_200M                                                   
C  NNAMEm0218 UNNAMED_515_ISL80101IRAJZDFN10_                                   
C  NNAMEm0219 UNNAMED_515_CAPACITOR_I138_1                                      
C  NNAMEm0220 UNNAMED_515_CAPACITOR_I132_1                                      
C  NNAMEm0221 UNNAMED_515_CAPACITOR_I130_1                                      
C  NNAMEm0222 UNNAMED_515_CAPACITOR_I128_1                                      
C  NNAMEm0223 UNNAMED_14_RESISTOR_I65_2                                         
C  NNAMEm0224 UNNAMED_14_RESISTOR_I58_2                                         
C  NNAMEm0225 UNNAMED_14_OPTICAL_I140_A                                         
C  NNAMEm0226 UNNAMED_14_OPTICAL_I141_A                                         
C  NNAMEm0227 UNNAMED_14_OPTICAL_I143_A                                         
C  NNAMEm0228 UNNAMED_14_OPTICAL_I142_A                                         
C  NNAMEm0229 UNNAMED_14_OPTICAL_I292_A                                         
C  NNAMEm0230 UNNAMED_127_MT25QL128ABA1ESES_3                                   
C  NNAMEm0231 UNNAMED_127_MT25QL128ABA1ESES_2                                   
C  NNAMEm0232 UNNAMED_127_MT25QL128ABA1ESES_1                                   
C  NNAMEm0233 UNNAMED_127_MT25QL128ABA1ESESOP                                   
C  NNAMEm0234 UART_MAC_TX_FPGA_RX                                               
C  NNAMEm0235 UART_MAC_RX_FPGA_TX                                               
C  NNAMEm0236 UART_GPS_TX_FPGA_RX                                               
C  NNAMEm0237 UART_GPS_RX_FPGA_TX                                               
C  NNAMEm0238 R_PCA9546_I2C_SDA                                                 
C  NNAMEm0239 R_PCA9546_I2C_SCL                                                 
C  NNAMEm0240 MHZ200CLKP_CLKIN                                                  
C  NNAMEm0241 MHZ200CLKN_CLKIN                                                  
C  NNAMEm0242 MHZ125CLKP_CLKIN                                                  
C  NNAMEm0243 MHZ125CLKN_CLKIN                                                  
C  NNAMEm0244 FPGA_OUT_MAC_PPS_IN1P                                             
C  NNAMEm0245 FPGA_OUT_MAC_PPS_IN1N                                             
C  NNAMEm0246 FPGA_OUT_MAC_PPS_IN0P                                             
C  NNAMEm0247 FPGA_OUT_MAC_PPS_IN0N                                             
C  NNAMEm0248 FPGA_OUT_MACUSBPOWER_EN                                           
C  NNAMEm0249 FPGA_OUT_GPS_RST_N                                                
C  NNAMEm0250 FPGA_IN_MAC_PPS_OUTP                                              
C  NNAMEm0251 FPGA_IN_MAC_PPS_OUTN                                              
C  NNAMEm0252 XP5R0V_USB_CONN_DET                                               
C  NNAMEm0253 XP5R0V_USB_CONN                                                   
C  NNAMEm0254 XP5R0V_FB_R_TO_AGND                                               
C  NNAMEm0255 XP3R3V_FB_R_TO_AGND                                               
C  NNAMEm0256 XP12R0V_A_TIMER                                                   
C  NNAMEm0257 UNNAMED_517_CAPACITOR_I30_1                                       
C  NNAMEm0258 UNNAMED_517_CAPACITOR_I29_2                                       
C  NNAMEm0259 UNNAMED_517_CAPACITOR_I27_1                                       
C  NNAMEm0260 UNNAMED_517_CAPACITOR_I17_1                                       
C  NNAMEm0261 UNNAMED_516_CAPACITOR_I37_2                                       
C  NNAMEm0262 UNNAMED_516_CAPACITOR_I29_1                                       
C  NNAMEm0263 UNNAMED_516_CAPACITOR_I27_1                                       
C  NNAMEm0264 UNNAMED_516_CAPACITOR_I13_1                                       
C  NNAMEm0265 UNNAMED_3_G2201019801_I100_EN                                     
C  NNAMEm0266 UNNAMED_15_MP5022CGQVZQFN22_I_2                                   
C  NNAMEm0267 UNNAMED_15_MP5022CGQVZQFN22_I21                                   
C  NNAMEm0268 UNNAMED_127_G2001028301_I427_4                                    
C  NNAMEm0269 UNNAMED_12_74HCT2G125DPTSSOP8_I                                   
C  NNAMEm0270 UNNAMED_12_74HCT2G125DPTSSOP8_3                                   
C  NNAMEm0271 UNNAMED_527_RESISTOR_I201_2                                       
C  NNAMEm0272 UNNAMED_527_RESISTOR_I126_1                                       
C  NNAMEm0273 PCIE_CONN_SMDAT                                                   
C  NNAMEm0274 PCIE_CONN_SMCLK                                                   
C  NNAMEm0275 ANALOG_TUNING_IN                                                  
C  NNAMEm0276 XP3R3V_AUX_PCIE                                                   
C  NNAMEm0277 UNNAMED_9_CAPACITOR_I17_1                                         
C  NNAMEm0278 R_LM75B_1_I2C_SDA                                                 
C  NNAMEm0279 UNNAMED_6_LM75BDPTSSOP8_I34_A2                                    
C  NNAMEm0280 UNNAMED_6_LM75BDPTSSOP8_I34_A1                                    
C  NNAMEm0281 UNNAMED_6_LM75BDPTSSOP8_I34_A0                                    
C  NNAMEm0282 UNNAMED_5_PCA9546APWTSSOP16_I_2                                   
C  NNAMEm0283 UNNAMED_5_PCA9546APWTSSOP16_I_1                                   
C  NNAMEm0284 UNNAMED_5_PCA9546APWTSSOP16_I33                                   
C  NNAMEm0285 UNNAMED_3_CONN64PGF_I61_PRSNT22                                   
C  NNAMEm0286 UNNAMED_3_CONN64PGF_I61_PRSNT21                                   
C  NNAMEm0287 UNNAMED_14_OPTICAL_I137_A                                         
C  NNAMEm0288 UNNAMED_14_OPTICAL_I12_A                                          
C  NNAMEm0289 UNNAMED_14_OPTICAL_I11_A                                          
C  NNAMEm0290 UNNAMED_14_OPTICAL_I136_A                                         
C  NNAMEm0291 R_SHT3X_I2C_SDA                                                   
C  NNAMEm0292 R_SHT3X_I2C_SCL                                                   
C  NNAMEm0293 R_MAC_UART_TX_FPGA_RX                                             
C  NNAMEm0294 R_MAC_UART_RX_FPGA_TX                                             
C  NNAMEm0295 R_MAC_10MHZ_RF_OUT                                                
C  NNAMEm0296 R_ICP10100_I2C_SDA                                                
C  NNAMEm0297 R_ICP10100_I2C_SCL                                                
C  NNAMEm0298 R_BNO080_BOOT_N                                                   
C  NNAMEm0299 PCIE_CONN_PERST_N                                                 
C  NNAMEm0300 PCA9546_I2C_SDA                                                   
C  NNAMEm0301 PCA9546_I2C_SCL                                                   
C  NNAMEm0302 ICP10100_I2C_SDA                                                  
C  NNAMEm0303 ICP10100_I2C_SCL                                                  
C  NNAMEm0304 C_CPU_RX_PCIE_MGT3_TXP                                            
C  NNAMEm0305 C_CPU_RX_PCIE_MGT3_TXN                                            
C  NNAMEm0306 C_CPU_RX_PCIE_MGT2_TXP                                            
C  NNAMEm0307 C_CPU_RX_PCIE_MGT2_TXN                                            
C  NNAMEm0308 C_CPU_RX_PCIE_MGT1_TXP                                            
C  NNAMEm0309 C_CPU_RX_PCIE_MGT1_TXN                                            
C  NNAMEm0310 C_CPU_RX_PCIE_MGT0_TXP                                            
C  NNAMEm0311 C_CPU_RX_PCIE_MGT0_TXN                                            
C  NNAMEm0312 CPU_TX_PCIE_MGT_3_RXP                                             
C  NNAMEm0313 CPU_TX_PCIE_MGT_3_RXN                                             
C  NNAMEm0314 CPU_TX_PCIE_MGT_2_RXP                                             
C  NNAMEm0315 CPU_TX_PCIE_MGT_2_RXN                                             
C  NNAMEm0316 CPU_TX_PCIE_MGT_1_RXP                                             
C  NNAMEm0317 CPU_TX_PCIE_MGT_1_RXN                                             
C  NNAMEm0318 CPU_TX_PCIE_MGT_0_RXP                                             
C  NNAMEm0319 CPU_TX_PCIE_MGT_0_RXN                                             
C  NNAMEm0320 CPU_RX_PCIE_MGT3_TXP                                              
C  NNAMEm0321 CPU_RX_PCIE_MGT3_TXN                                              
C  NNAMEm0322 CPU_RX_PCIE_MGT2_TXP                                              
C  NNAMEm0323 CPU_RX_PCIE_MGT2_TXN                                              
C  NNAMEm0324 CPU_RX_PCIE_MGT1_TXP                                              
C  NNAMEm0325 CPU_RX_PCIE_MGT1_TXN                                              
C  NNAMEm0326 CPU_RX_PCIE_MGT0_TXP                                              
C  NNAMEm0327 CPU_RX_PCIE_MGT0_TXN                                              
C  NNAMEm0328 BF_PCIE_PERST_N                                                   
C                                                                               
C  ****************************************                                     
C      SIGNAL PINS & VIAS ON THE BOARD                                          
C  ****************************************                                     
C                                                                               
327m0000            U33   -6          A01X+042391Y+040314X0490Y0120R180 S1      
327m0000            R317  -2          A10X+042660Y+040650X0280Y0240R180 S2      
327m0000            R321  -2          A10X+043540Y+040650X0280Y0240     S2      
317m0000            VIA   -    MD0100PA00X+043100Y+040650X0200Y0200     S3      
327m0000            R364  -2          A01X+043540Y+040650X0280Y0240R180 S1      
327m0001            U33   -7          A01X+042406Y+040511X0460Y0120R180 S1      
327m0001            R318  -2          A10X+042660Y+041150X0280Y0240R180 S2      
327m0001            R322  -2          A10X+043540Y+041150X0280Y0240     S2      
317m0001            VIA   -    MD0100PA00X+043100Y+041150X0200Y0200     S3      
327m0001            R366  -2          A01X+043540Y+041150X0280Y0240R180 S1      
317FPGA_FCS_B       VIA   -    MD0100PA00X+046100Y+023000X0200Y0200     S3      
327FPGA_FCS_B       R362  -1          A01X+046500Y+022990X0280Y0240R090 S1      
317FPGA_FCS_B       VIA   -    MD0080PA00X+045018Y+020600X0180Y0180     S0      
327FPGA_FCS_B       U24   -T19        A01X+044822Y+020403X0197Y0197R090 S1      
317FPGA_D03         VIA   -    MD0100PA00X+044900Y+022750X0200Y0200     S3      
327FPGA_D03         R348  -1          A01X+046200Y+024190X0280Y0240R090 S1      
327FPGA_D03         U24   -R21        A01X+044428Y+021190X0197Y0197R090 S1      
317FPGA_D02         VIA   -    MD0100PA00X+044350Y+023150X0200Y0200     S3      
327FPGA_D02         R339  -1          A01X+045300Y+024190X0280Y0240R090 S1      
327FPGA_D02         U24   -P21        A01X+044034Y+021190X0197Y0197R090 S1      
317FPGA_D01         VIA   -    MD0100PA00X+044900Y+023250X0200Y0200     S3      
327FPGA_D01         R238  -1          A01X+045350Y+023240X0280Y0240R090 S1      
327FPGA_D01         U24   -R22        A01X+044428Y+021584X0197Y0197R090 S1      
317FPGA_D00_MOSI    VIA   -    MD0100PA00X+044350Y+023650X0200Y0200     S3      
327FPGA_D00_MOSI    R234  -1          A01X+044850Y+024190X0280Y0240R090 S1      
327FPGA_D00_MOSI    U24   -P22        A01X+044034Y+021584X0197Y0197R090 S1      
327m0002            R164  -2          A01X+037600Y+024260X0280Y0240R090 S1      
317m0002            VIA   -    MD0100PA00X+036550Y+024650X0200Y0200     S3      
327m0002            U34   -4          A01X+036576Y+025135X0200Y0470     S1      
327m0002            C250  -1   M      A01X+037050Y+024260X0280Y0240R270 S1      
327PCIE_PERST_N     R57   -2          A01X+029960Y+005744X0280Y0240     S1      
327PCIE_PERST_N     R63   -2   M      A01X+029970Y+006210X0280Y0240     S1      
317PCIE_PERST_N     VIA   -    MD0100PA00X+031250Y+016050X0200Y0200     S3      
317PCIE_PERST_N     VIA   -    MD0100PA00X+036500Y+026800X0200Y0200     S3      
327PCIE_PERST_N     U34   -3          A01X+036576Y+026265X0200Y0470     S1      
317PCIE_PERST_N     VIA   -    MD0100PA00X+031200Y+026450X0200Y0200     S3      
317m0003            VIA   -    MD0080PA00X+041869Y+020993X0180Y0180     S0      
327m0003            U24   -J20        A01X+042066Y+020796X0197Y0197R090 S1      
317m0003            VIA   -    MD0100PA00X+037650Y+026900X0200Y0200     S3      
327m0003            U34   -1          A01X+037324Y+026265X0200Y0470     S1      
327m0003            R167  -2   M      A01X+037310Y+027100X0280Y0240     S1      
327m0004            U33   -1          A01X+042406Y+039329X0460Y0120R180 S1      
317m0004            TP25  -1   MD0100PA00X+043000Y+038650X0200Y0200     S2      
327m0004            R320  -2          A01X+043540Y+038650X0280Y0240R180 S1      
327m0004            R319  -2          A10X+043540Y+038650X0280Y0240     S2      
327m0004            C316  -1          A10X+042400Y+039410X0280Y0240R270 S2      
317PCA9546_RST_N    VIA   -    MD0080PA00X+033652Y+033050X0180Y0180R090 S3      
327PCA9546_RST_N    U4    -3          A01X+032815Y+032766X0140Y0620R270 S1      
317PCA9546_RST_N    TP21  -1   MD0100PA00X+033700Y+034400X0200Y0200     S2      
327PCA9546_RST_N    R146  -2          A10X+032980Y+033850X0280Y0240R180 S2      
327PCA9546_RST_N    R60   -2   M      A10X+032980Y+034750X0280Y0240R180 S2      
327PCA9546_RST_N    R155  -2   M      A10X+032980Y+034300X0280Y0240R180 S2      
317MUX3_SEL         TP12  -1   MD0100PA00X+047950Y+009250X0200Y0200     S2      
327MUX3_SEL         U37   -1          A01X+048855Y+009196X0140Y0620R090 S1      
327MUX3_SEL         R485  -2          A01X+047360Y+009650X0280Y0240     S1      
327MUX3_SEL         R486  -2   M      A01X+047360Y+009150X0280Y0240     S1      
327MUX3_SEL         R482  -2          A10X+047360Y+009650X0280Y0240R180 S2      
327MUX3_SEL         R483  -2   M      A10X+047360Y+009150X0280Y0240R180 S2      
317MUX2_SEL         TP13  -1   MD0100PA00X+040800Y+032700X0200Y0200     S2      
327MUX2_SEL         U40   -6          A01X+042006Y+034076X0240Y0170R270 S1      
327MUX2_SEL         U38   -1          A01X+041695Y+032456X0140Y0620R090 S1      
327MUX2_SEL         R457  -2   M      A10X+040150Y+032910X0280Y0240R180 S2      
327MUX2_SEL         R458  -2          A10X+040150Y+032390X0280Y0240R180 S2      
327MUX2_SEL         R461  -2   M      A01X+040150Y+032910X0280Y0240     S1      
327MUX2_SEL         R462  -2          A01X+040150Y+032390X0280Y0240     S1      
327MUX2_SEL         U39   -6          A01X+040056Y+034056X0240Y0170R270 S1      
317MUX1_SEL         TP14  -1   MD0100PA00X+039500Y+038200X0200Y0200     S2      
327MUX1_SEL         U30   -1          A01X+040355Y+037646X0140Y0620R090 S1      
327MUX1_SEL         R449  -1          A01X+038810Y+037580X0280Y0240R180 S1      
327MUX1_SEL         R448  -1   M      A01X+038810Y+038100X0280Y0240R180 S1      
327MUX1_SEL         R450  -1   M      A10X+038810Y+038100X0280Y0240     S2      
327MUX1_SEL         R451  -1          A10X+038810Y+037580X0280Y0240     S2      
327FPGA_MGTRREF     R196  -2          A10X+037460Y+017200X0280Y0240R180 S2      
317FPGA_MGTRREF     TP47  -1   MD0100PA00X+037460Y+017820X0200Y0200     S2      
327FPGA_MGTRREF     U24   -F8         A01X+040885Y+016072X0197Y0197R090 S1      
317FPGA_MGTRREF     VIA   -    MD0080PA00X+040688Y+015875X0180Y0180     S0      
317CLK_200M_OE      TP49  -1   MD0100PA00X+042050Y+008200X0200Y0200     S2      
327CLK_200M_OE      R235  -2          A01X+042050Y+008790X0280Y0240R270 S1      
327CLK_200M_OE      Y3    -1          A01X+043140Y+008237X0350Y0250R090 S1      
317CLK_125M_OE      VIA   -    MD0100PA00X+038229Y+008621X0200Y0200     S3      
317CLK_125M_OE      TP50  -1    D0100PA00X+037050Y+008400X0200Y0200     S2      
327CLK_125M_OE      Y4    -1          A01X+038800Y+007522X0390Y0550R090 S1      
327CLK_125M_OE      R236  -2   M      A01X+037700Y+008740X0280Y0240R270 S1      
327m0005            C318  -2          A01X+004956Y+021660X0120Y0150R180 S1      
317m0005            VIA   -    MD0100PA00X+004960Y+021346X0200Y0200     S3      
327m0005            R495  -1          A10X+005300Y+020910X0280Y0240R090 S2      
327m0006            C317  -2          A01X+005174Y+026800X0120Y0150     S1      
317m0006            VIA   -    MD0100PA00X+005280Y+027200X0200Y0200     S3      
327m0006            R494  -1          A10X+005300Y+026260X0280Y0240R090 S2      
327m0007            R493  -1          A10X+005350Y+009260X0280Y0240R090 S2      
327m0007            C311  -2          A01X+005244Y+010000X0120Y0150     S1      
317m0007            VIA   -    MD0100PA00X+005750Y+010150X0200Y0200     S3      
327m0008            C310  -2          A01X+004896Y+015700X0120Y0150R180 S1      
327m0008            R492  -1          A10X+005300Y+014860X0280Y0240R090 S2      
317m0008            VIA   -    MD0100PA00X+004896Y+015362X0200Y0200     S3      
327XP5R0V_FT4232    R18   -1          A10X+010550Y+037310X0280Y0240R090 S2      
317XP5R0V_FT4232    VIA   -    MD0100PA00X+014500Y+035900X0200Y0200     S3      
317XP5R0V_FT4232    VIA   -    MD0100PA00X+015600Y+031650X0200Y0200     S3      
317XP5R0V_FT4232    VIA   -    MD0100PA00X+015600Y+032050X0200Y0200     S3      
327XP5R0V_FT4232    CR2   -A          A01X+015967Y+031700X0200Y0200R180 S1      
327XP5R0V_FT4232    C94   -1          A10X+007000Y+034260X0280Y0240R090 S2      
327XP5R0V_FT4232    U17   -5          A01X+007200Y+035065X0200Y0470R180 S1      
317XP5R0V_FT4232    VIA   -    MD0100PA00X+007200Y+034630X0200Y0200     S3      
317XP5R0V_FT4232    J13   -A9   D0160PA00X+004233Y+034315X0240Y0240R270 S3      
317XP5R0V_FT4232    J13   -B4   D0160PA00X+004055Y+034008X0240Y0240R270 S3      
317XP5R0V_FT4232    J13   -A4   D0160PA00X+002815Y+034315X0240Y0240R270 S3      
317XP5R0V_FT4232    J13   -B9   D0160PA00X+002638Y+034008X0240Y0240R270 S3      
317XP5R0V_FT4232    TP4   -1    D0100PA00X+007100Y+033050X0200Y0200R270 S2      
327XP3R3V_VPLL      C98   -1          A10X+010850Y+035640X0280Y0240R270 S2      
327XP3R3V_VPLL      C100  -1          A10X+011300Y+035640X0280Y0240R270 S2      
327XP3R3V_VPLL      L4    -2          A10X+010900Y+035120X0300Y0340R270 S2      
327XP3R3V_VPLL      U18   -9          A01X+011132Y+035780X0120Y0640     S1      
317XP3R3V_VPLL      VIA   -    MD0100PA00X+011400Y+035200X0200Y0200     S3      
317XP3R3V_VPHY      VIA   -    MD0100PA00X+012450Y+035200X0200Y0200     S3      
327XP3R3V_VPHY      U18   -4          A01X+012116Y+035780X0120Y0640     S1      
327XP3R3V_VPHY      C99   -1   M      A10X+012200Y+035640X0280Y0240R270 S2      
327XP3R3V_VPHY      C101  -1   M      A10X+012650Y+035640X0280Y0240R270 S2      
327XP3R3V_VPHY      L22   -2          A10X+013200Y+035480X0300Y0340R090 S2      
327XP3R3V_GPS       L16   -1          A01X+046520Y+038600X0300Y0340R180 S1      
317XP3R3V_GPS       VIA   -    MD0080PA00X+047050Y+039500X0180Y0180R180 S3      
327XP3R3V_GPS       P2    -2          A01X+047866Y+039083X0400Y0880R090 S1      
327XP3R3V_GPS       C79   -1          A01X+046540Y+039270X0380Y0540R180 S1      
327XP3R3V_GPS       R115  -1          A10X+047780Y+035510X0280Y0240     S2      
317XP3R3V_GPS       VIA   -    MD0100PA00X+047050Y+039100X0200Y0200     S3      
327XP3R3V_GPS       C80   -1          A10X+046560Y+038950X0280Y0240     S2      
327XP3R3V_GPS       C273  -1          A10X+046560Y+039400X0280Y0240     S2      
327XP3R3V_FT_PG     U41   -4          A01X+016203Y+029953X0410Y0120     S1      
317XP3R3V_FT_PG     VIA   -    MD0100PA00X+015660Y+029500X0200Y0200     S3      
327XP3R3V_FT_PG     R456  -1          A01X+010550Y+037310X0280Y0240R270 S1      
317XP3R3V_FT_PG     VIA   -    MD0100PA00X+010450Y+037700X0200Y0200     S3      
317XP3R3V_FT4232    VIA   -    MD0100PA00X+015150Y+035800X0200Y0200     S3      
317XP3R3V_FT4232    VIA   -    MD0100PA00X+061450Y+040350X0200Y0200     S3      
327XP3R3V_FT4232    R169  -2          A10X+061450Y+040940X0280Y0240R090 S2      
317XP3R3V_FT4232    VIA   -    MD0100PA00X+013700Y+036400X0200Y0200     S3      
327XP3R3V_FT4232    L22   -1          A10X+013200Y+036020X0300Y0340R090 S2      
327XP3R3V_FT4232    C91   -1   M      A10X+013750Y+036010X0280Y0240R090 S2      
317XP3R3V_FT4232    VIA   -    MD0100PA00X+016670Y+034380X0200Y0200     S3      
327XP3R3V_FT4232    U31   -6          A10X+017485Y+034380X0200Y0650R270 S2      
317XP3R3V_FT4232    VIA   -    MD0100PA00X+015910Y+035460X0200Y0200     S3      
327XP3R3V_FT4232    U31   -8          A10X+017485Y+035380X0200Y0650R270 S2      
327XP3R3V_FT4232    C88   -1   M      A10X+016300Y+035460X0280Y0240R090 S2      
317XP3R3V_FT4232    VIA   -    MD0100PA00X+011300Y+034450X0200Y0200     S3      
327XP3R3V_FT4232    L4    -1          A10X+010900Y+034580X0300Y0340R270 S2      
327XP3R3V_FT4232    C95   -1          A10X+011540Y+034750X0280Y0240R180 S2      
327XP3R3V_FT4232    U18   -20         A01X+008940Y+034376X0120Y0640R090 S1      
317XP3R3V_FT4232    VIA   -    MD0100PA00X+009500Y+034450X0200Y0200     S3      
327XP3R3V_FT4232    R466  -2          A10X+009110Y+034550X0280Y0240R180 S2      
327XP3R3V_FT4232    R444  -1          A10X+021460Y+033600X0280Y0240     S2      
327XP3R3V_FT4232    R446  -1          A10X+021460Y+035500X0280Y0240     S2      
317XP3R3V_FT4232    VIA   -    MD0100PA00X+021900Y+034880X0200Y0200     S3      
327XP3R3V_FT4232    R447  -1   M      A10X+021460Y+035000X0280Y0240     S2      
317XP3R3V_FT4232    VIA   -    MD0100PA00X+021920Y+033880X0200Y0200     S3      
317XP3R3V_FT4232    VIA   -    MD0100PA00X+014192Y+033392X0200Y0200     S3      
327XP3R3V_FT4232    U18   -56         A01X+013520Y+033392X0120Y0640R090 S1      
327XP3R3V_FT4232    U18   -50         A01X+013520Y+032210X0120Y0640R090 S1      
317XP3R3V_FT4232    VIA   -    MD0100PA00X+014070Y+032000X0200Y0200     S3      
327XP3R3V_FT4232    R349  -2          A10X+013810Y+032350X0280Y0240R180 S2      
317XP3R3V_FT4232    VIA   -    MD0100PA00X+014950Y+031103X0200Y0200     S3      
327XP3R3V_FT4232    U41   -2          A01X+016203Y+030347X0410Y0120     S1      
327XP3R3V_FT4232    U41   -1          A01X+016203Y+030544X0410Y0210R180 S1      
327XP3R3V_FT4232    L24   -2          A01X+014550Y+031380X0300Y0340R270 S1      
327XP3R3V_FT4232    C308  -1          A01X+014600Y+030730X0380Y0540R270 S1      
327XP3R3V_FT4232    C309  -1          A01X+015100Y+031640X0280Y0240R090 S1      
317XP3R3V_FT4232    TP3   -1   MD0100PA00X+015350Y+031050X0200Y0200R270 S2      
327XP3R3V_FT4232    R490  -1          A01X+015300Y+030460X0280Y0240R270 S1      
317XP3R3V_FT4232    VIA   -    MD0100PA00X+011525Y+030625X0200Y0200     S3      
327XP3R3V_FT4232    U18   -42         A01X+011525Y+031200X0120Y0640     S1      
317XP3R3V_FT4232    VIA   -    MD0100PA00X+009500Y+032150X0200Y0200     S3      
327XP3R3V_FT4232    U18   -31         A01X+008940Y+032210X0120Y0640R090 S1      
317XP3R3V_FT4232    VIA   -    MD0100PA00X+009450Y+031250X0200Y0200     S3      
327XP3R3V_FT4232    R478  -2          A10X+007460Y+032450X0280Y0240R180 S2      
327XP3R3V_FT4232    R479  -2   M      A10X+007460Y+032000X0280Y0240R180 S2      
317XP3R3V_FT4232    VIA   -    MD0100PA00X+011750Y+029000X0200Y0200     S3      
327XP3R3V_FT4232    R481  -2          A01X+011750Y+029390X0280Y0240R270 S1      
317XP3R3V_FT4232    VIA   -    MD0100PA00X+010250Y+030200X0200Y0200     S3      
327XP3R3V_FT4232    R480  -2          A01X+010250Y+029810X0280Y0240R090 S1      
317XP12R0V_IN       VIA   -     D0100PA00X+052750Y+038910X0200Y0200     S3      
327XP12R0V_IN       R9    -1          A01X+053140Y+039020X0300Y0340     S1      
317XP12R0V_IN       VIA   -    MD0100PA00X+052750Y+039310X0200Y0200     S3      
317XP12R0V_IN       VIA   -    MD0100PA00X+052750Y+039710X0200Y0200     S3      
317XP12R0V_IN       VIA   -    MD0100PA00X+053210Y+039900X0200Y0200     S3      
327XP12R0V_IN       R11   -1          A01X+053200Y+039570X0280Y0240     S1      
327XP12R0V_IN       R4    -1          A01X+057620Y+034670X0280Y0240R180 S1      
317XP12R0V_IN       VIA   -    MD0080PA00X+057620Y+034250X0180Y0180     S3      
317XP12R0V_IN       VIA   -    MD0100PA00X+055670Y+032030X0200Y0200R270 S3      
317XP12R0V_IN       VIA   -    MD0100PA00X+056170Y+032030X0200Y0200R270 S3      
327XP12R0V_IN       CR10  -C          A01X+055509Y+033060X0940Y1300     S1      
317XP12R0V_IN       VIA   -    MD0100PA00X+056200Y+033160X0200Y0200R270 S3      
317XP12R0V_IN       VIA   -    MD0100PA00X+056250Y+032610X0200Y0200R270 S3      
317XP12R0V_IN       VIA   -    MD0100PA00X+056250Y+033610X0200Y0200R270 S3      
327XP12R0V_IN       FU1   -1          A01X+055330Y+035690X0300Y0340R180 S1      
317XP12R0V_IN       VIA   -    MD0100PA00X+056000Y+034210X0200Y0200R270 S3      
317XP12R0V_IN       VIA   -    MD0080PA00X+055520Y+037114X0180Y0180R270 S3      
327XP12R0V_IN       C2    -1          A01X+055950Y+035690X0280Y0240     S1      
317XP12R0V_IN       VIA   -    MD0080PA00X+055520Y+037468X0180Y0180R270 S3      
317XP12R0V_IN       VIA   -    MD0080PA00X+055520Y+037823X0180Y0180R270 S3      
317XP12R0V_IN       VIA   -    MD0080PA00X+055520Y+036760X0180Y0180     S3      
327XP12R0V_IN       C303  -1          A10X+055270Y+032060X0380Y0540     S2      
327XP12R0V_IN       C297  -1          A10X+055310Y+033640X0380Y0540     S2      
327XP12R0V_IN       C299  -1          A10X+055310Y+032880X0380Y0540     S2      
327XP12R0V_IN       C301  -1          A10X+055310Y+034410X0380Y0540     S2      
327XP12R0V_IN       U1    -23         A01X+055360Y+036937X0490Y0100R180 S0      
327XP12R0V_IN       U1    -24         A01X+055360Y+037291X0490Y0100R180 S0      
327XP12R0V_IN       U1    -21  M      A01X+055360Y+036581X0524Y0456R180 S1      
327XP12R0V_IN       U1    -22  M      A01X+055561Y+036330X0010Y0010R180 S1      
327XP12R0V_IN       U1    -25         A01X+055360Y+037646X0490Y0100R180 S0      
327XP12R0V_IN       U1    -26         A01X+055360Y+038000X0490Y0100R180 S0      
317XP12R0V_IN       VIA   -    MD0080PA00X+055200Y+037823X0180Y0180     S3      
317XP12R0V_IN       VIA   -    MD0080PA00X+055200Y+037468X0180Y0180     S3      
317XP12R0V_IN       VIA   -    MD0080PA00X+055200Y+037114X0180Y0180     S3      
317XP12R0V_IN       VIA   -    MD0080PA00X+055200Y+036760X0180Y0180     S3      
317XP12R0V_IN       TP42  -1   MD0100PA00X+009780Y+039180X0200Y0200     S2      
317XP12R0V_IN       VIA   -    MD0100PA00X+009280Y+039610X0200Y0200     S3      
317XP12R0V_IN       VIA   -    MD0100PA00X+009680Y+039610X0200Y0200     S3      
317XP12R0V_IN       VIA   -    MD0100PA00X+009680Y+040210X0200Y0200     S3      
317XP12R0V_IN       VIA   -    MD0100PA00X+009280Y+040210X0200Y0200     S3      
317XP12R0V_IN       VIA   -    MD0100PA00X+009280Y+040810X0200Y0200     S3      
317XP12R0V_IN       VIA   -    MD0100PA00X+009680Y+040810X0200Y0200     S3      
317XP12R0V_IN       VIA   -    MD0100PA00X+009280Y+041410X0200Y0200     S3      
317XP12R0V_IN       VIA   -    MD0100PA00X+009680Y+041410X0200Y0200     S3      
317XP12R0V_IN       VIA   -    MD0100PA00X+006030Y+039510X0200Y0200     S3      
317XP12R0V_IN       VIA   -    MD0100PA00X+006430Y+039560X0200Y0200     S3      
317XP12R0V_IN       VIA   -    MD0100PA00X+006030Y+040110X0200Y0200     S3      
317XP12R0V_IN       VIA   -    MD0100PA00X+006430Y+040160X0200Y0200     S3      
317XP12R0V_IN       VIA   -    MD0100PA00X+006030Y+040710X0200Y0200     S3      
317XP12R0V_IN       VIA   -    MD0100PA00X+006430Y+040760X0200Y0200     S3      
317XP12R0V_IN       VIA   -    MD0100PA00X+006030Y+041310X0200Y0200     S3      
317XP12R0V_IN       VIA   -    MD0100PA00X+006430Y+041360X0200Y0200     S3      
327XP12R0V_IN       L20   -2          A01X+005710Y+038990X0300Y0340R090 S1      
317XP12R0V_IN       VIA   -    MD0100PA00X+008540Y+039420X0200Y0200     S3      
317XP12R0V_IN       VIA   -    MD0100PA00X+008070Y+039420X0200Y0200     S3      
317XP12R0V_IN       VIA   -    MD0100PA00X+007600Y+039420X0200Y0200     S3      
317XP12R0V_IN       VIA   -    MD0100PA00X+007130Y+039420X0200Y0200     S3      
317XP12R0V_IN       VIA   -    MD0100PA00X+007600Y+040420X0200Y0200     S3      
317XP12R0V_IN       VIA   -    MD0100PA00X+007600Y+039920X0200Y0200     S3      
317XP12R0V_IN       VIA   -    MD0100PA00X+007130Y+039920X0200Y0200     S3      
317XP12R0V_IN       VIA   -    MD0100PA00X+007130Y+040420X0200Y0200     S3      
317XP12R0V_IN       VIA   -    MD0100PA00X+007130Y+040920X0200Y0200     S3      
317XP12R0V_IN       VIA   -    MD0100PA00X+007600Y+040920X0200Y0200     S3      
317XP12R0V_IN       VIA   -    MD0100PA00X+008070Y+040920X0200Y0200     S3      
317XP12R0V_IN       VIA   -    MD0100PA00X+008070Y+040420X0200Y0200     S3      
317XP12R0V_IN       VIA   -    MD0100PA00X+008070Y+039920X0200Y0200     S3      
317XP12R0V_IN       VIA   -    MD0100PA00X+008540Y+039920X0200Y0200     S3      
317XP12R0V_IN       VIA   -    MD0100PA00X+008540Y+040420X0200Y0200     S3      
317XP12R0V_IN       VIA   -    MD0100PA00X+008540Y+040920X0200Y0200     S3      
327XP12R0V_IN       CR12  -3   M      A01X+007830Y+040180X2280Y2440     S0      
327m0009            R163  -1          A10X+006980Y+009530X0280Y0240R090 S2      
327m0009            R162  -2   M      A10X+007430Y+009530X0280Y0240R270 S2      
317m0009            VIA   -    MD0100PA00X+007400Y+010050X0200Y0200R090 S3      
327m0009            U19   -3          A01X+007622Y+009475X0620Y0140R270 S1      
317m0010            VIA   -    MD0100PA00X+007900Y+010050X0200Y0200R090 S3      
327m0010            U19   -2          A01X+007878Y+009475X0620Y0140R270 S1      
327m0010            R161  -1          A10X+008330Y+009530X0280Y0240R090 S2      
327m0010            R160  -2   M      A10X+007880Y+009530X0280Y0240R270 S2      
327m0011            U19   -1          A01X+008134Y+009475X0620Y0140R270 S1      
317m0011            VIA   -    MD0100PA00X+008400Y+010050X0200Y0200R090 S3      
327m0011            R159  -1   M      A10X+008780Y+009530X0280Y0240R090 S2      
327m0011            R158  -2          A10X+013510Y+007530X0280Y0240R180 S2      
327m0012            U41   -3          A01X+016203Y+030150X0410Y0120     S1      
327m0012            R491  -1          A10X+015210Y+030000X0280Y0240     S2      
317m0012            VIA   -    MD0100PA00X+015680Y+030110X0200Y0200     S3      
327m0012            R489  -1          A01X+015260Y+029500X0280Y0240R180 S1      
327m0012            R490  -2   M      A01X+015300Y+030040X0280Y0240R270 S1      
317m0013            VIA   -     D0100PA00X+017380Y+032410X0200Y0200     S3      
327m0013            C298  -1          A01X+018190Y+031900X0280Y0240     S1      
327m0013            C284  -1          A01X+017820Y+032600X0380Y0540     S1      
327m0013            CR2   -C          A01X+016833Y+031700X0200Y0200R180 S1      
327m0013            CR1   -C          A01X+016833Y+032700X0200Y0200R180 S1      
327m0013            L23   -1          A01X+017600Y+031870X0300Y0340R270 S1      
327m0014            U41   -6          A01X+017397Y+029756X0410Y0210     S1      
317m0014            VIA   -     D0100PA00X+017650Y+029000X0200Y0200     S3      
327m0014            C307  -1   M      A01X+017354Y+029000X0120Y0150R180 S1      
327m0015            U41   -9          A01X+017397Y+030347X0410Y0120     S1      
327m0015            U41   -10         A01X+017397Y+030544X0410Y0210R180 S1      
327m0015            C300  -1          A01X+018220Y+031050X0380Y0540     S1      
317m0015            VIA   -     D0100PA00X+017800Y+030950X0200Y0200     S3      
327m0015            R487  -1          A01X+018350Y+029810X0280Y0240R270 S1      
327m0015            L23   -2          A01X+017600Y+031330X0300Y0340R270 S1      
327m0015            C304  -1          A01X+018240Y+030400X0280Y0240     S1      
327m0016            U41   -7          A01X+017397Y+029953X0410Y0120     S1      
327m0016            R488  -1          A10X+018850Y+029390X0280Y0240R270 S2      
317m0016            VIA   -    MD0100PA00X+017950Y+029460X0200Y0200     S3      
327m0016            C302  -1          A01X+018850Y+029390X0280Y0240R090 S1      
327m0016            R487  -2   M      A01X+018350Y+029390X0280Y0240R270 S1      
317m0017            VIA   -    MD0100PA00X+052000Y+008700X0200Y0200     S3      
327m0017            R484  -2          A01X+052490Y+008700X0280Y0240R180 S1      
327m0017            U37   -15         A01X+051245Y+008940X0140Y0620R090 S1      
317m0018            VIA   -    MD0100PA00X+044700Y+032200X0200Y0200     S3      
327m0018            U38   -15         A01X+044085Y+032200X0140Y0620R090 S1      
327m0018            R459  -2          A01X+045120Y+032200X0280Y0240R180 S1      
317m0019            VIA   -    MD0100PA00X+043850Y+036450X0200Y0200     S3      
327m0019            R453  -1   M      A01X+043840Y+037450X0280Y0240     S1      
327m0019            R452  -1   M      A01X+043840Y+037000X0280Y0240     S1      
327m0019            Q1    -3          A01X+044350Y+036185X0390Y0550     S1      
327m0019            U30   -15         A01X+042745Y+037390X0140Y0620R090 S1      
317m0020            TP5   -1    D0100PA00X+007800Y+033050X0200Y0200     S2      
327m0020            U18   -24         A01X+008940Y+033588X0120Y0640R090 S1      
327m0021            R460  -2          A10X+010400Y+035640X0280Y0240R090 S2      
317m0021            VIA   -    MD0100PA00X+010300Y+035150X0200Y0200     S3      
327m0021            U18   -14         A01X+010147Y+035780X0120Y0640     S1      
327m0022            R463  -1          A10X+011750Y+035640X0280Y0240R270 S2      
317m0022            VIA   -    MD0100PA00X+011900Y+035200X0200Y0200     S3      
327m0022            U18   -6          A01X+011722Y+035780X0120Y0640     S1      
327m0023            U18   -34         A01X+009950Y+031200X0120Y0640     S1      
317m0023            TP10  -1    D0100PA00X+009500Y+029150X0200Y0200R090 S2      
327m0024            U18   -33         A01X+009754Y+031200X0120Y0640     S1      
317m0024            TP9   -1    D0100PA00X+009450Y+029900X0200Y0200     S2      
327m0025            U18   -32         A01X+008940Y+032014X0120Y0640R090 S1      
317m0025            TP8   -1    D0100PA00X+008850Y+030300X0200Y0200R090 S2      
317m0026            TP7   -1    D0100PA00X+008750Y+029550X0200Y0200     S2      
327m0026            U18   -30         A01X+008940Y+032407X0120Y0640R090 S1      
317m0027            TP6   -1    D0100PA00X+007950Y+030850X0200Y0200     S2      
327m0027            U18   -29         A01X+008940Y+032604X0120Y0640R090 S1      
317m0028            VIA   -    MD0100PA00X+005500Y+033600X0200Y0200     S3      
327m0028            R445  -1          A01X+005890Y+032900X0280Y0240     S1      
317m0028            J13   -B5   D0160PA00X+003701Y+034008X0240Y0240R270 S3      
317m0029            VIA   -    MD0100PA00X+005500Y+035540X0200Y0200     S3      
327m0029            R442  -1          A01X+005950Y+035540X0280Y0240R090 S1      
317m0029            J13   -A5   D0160PA00X+003169Y+034315X0240Y0240R270 S3      
327m0030            U18   -2          A01X+012510Y+035780X0120Y0640     S1      
327m0030            Y2    -1          A01X+012983Y+039185X0550Y0470R180 S1      
327m0030            C86   -2   M      A01X+012696Y+037900X0120Y0150R180 S1      
327m0030            R455  -1   M      A01X+012710Y+037500X0280Y0240R180 S1      
327m0031            U18   -3          A01X+012313Y+035780X0120Y0640     S1      
327m0031            Y2    -3          A01X+012117Y+038515X0550Y0470R180 S1      
327m0031            C87   -2   M      A01X+012354Y+037900X0120Y0150     S1      
327m0031            R455  -2   M      A01X+012290Y+037500X0280Y0240R180 S1      
327m0032            R432  -1          A10X+059800Y+015810X0280Y0240R090 S2      
327m0032            J5    -6          A01X+059945Y+015706X0560Y0880R090 S1      
317m0032            VIA   -    MD0100PA00X+059200Y+015706X0200Y0200     S3      
327m0033            J5    -5          A01X+061465Y+015706X0560Y0920R090 S1      
327m0033            R428  -2          A10X+061700Y+015760X0280Y0240R270 S2      
317m0033            VIA   -    MD0100PA00X+062200Y+015700X0200Y0200     S3      
327m0034            R431  -1          A10X+059800Y+014610X0280Y0240R090 S2      
317m0034            VIA   -    MD0100PA00X+059200Y+014600X0200Y0200     S3      
327m0034            J5    -8          A01X+059945Y+014706X0560Y0880R090 S1      
327m0035            R329  -2          A10X+061700Y+014760X0280Y0240R270 S2      
317m0035            VIA   -    MD0100PA00X+062200Y+014650X0200Y0200R180 S3      
327m0035            J5    -7          A01X+061465Y+014706X0560Y0920R090 S1      
327m0036            R433  -1          A10X+059800Y+016760X0280Y0240R090 S2      
317m0036            VIA   -    MD0100PA00X+059200Y+016800X0200Y0200     S3      
327m0036            J5    -4          A01X+059945Y+016706X0560Y0880R090 S1      
327m0037            R429  -2          A10X+061700Y+016760X0280Y0240R270 S2      
317m0037            VIA   -    MD0100PA00X+062204Y+016706X0200Y0200R180 S3      
327m0037            J5    -3          A01X+061465Y+016706X0560Y0920R090 S1      
327m0038            R434  -1          A10X+059800Y+017810X0280Y0240R090 S2      
317m0038            VIA   -    MD0100PA00X+059200Y+017800X0200Y0200     S3      
327m0038            J5    -2          A01X+059945Y+017706X0560Y0880R090 S1      
327m0039            R430  -2          A10X+061550Y+017690X0280Y0240R090 S2      
317m0039            VIA   -    MD0100PA00X+062200Y+017550X0200Y0200R180 S3      
327m0039            J5    -1          A01X+061465Y+017706X0560Y0920R090 S1      
327m0040            R169  -1          A10X+061450Y+041360X0280Y0240R090 S2      
317m0040            VIA   -    MD0100PA00X+060942Y+041378X0200Y0200     S3      
327m0040            DS12  -A          A01X+061437Y+041378X0310Y0310R270 S1      
317m0041            VIA   -    MD0100PA00X+035100Y+030800X0200Y0200     S3      
317m0041            VIA   -    MD0100PA00X+010250Y+029000X0200Y0200     S3      
327m0041            R480  -1   M      A01X+010250Y+029390X0280Y0240R090 S1      
327m0041            R353  -2          A01X+010750Y+029390X0280Y0240R270 S1      
327m0041            U24   -P16        A01X+044034Y+019222X0197Y0197R090 S1      
317m0041            VIA   -    MD0080PA00X+044231Y+019418X0180Y0180     S0      
317m0042            VIA   -    MD0100PA00X+034600Y+030650X0200Y0200     S3      
317m0042            VIA   -    MD0100PA00X+011250Y+029000X0200Y0200     S3      
327m0042            R352  -2          A01X+011250Y+029390X0280Y0240R270 S1      
327m0042            U24   -P15        A01X+044034Y+018828X0197Y0197R090 S1      
317m0042            VIA   -    MD0080PA00X+044231Y+019025X0180Y0180     S0      
317SN_EEPROM_WP     VIA   -    MD0100PA00X+030350Y+016400X0200Y0200     S3      
317SN_EEPROM_WP     TP19  -1   MD0100PA00X+034450Y+026500X0200Y0200     S2      
327SN_EEPROM_WP     J17   -1          A01X+034426Y+027650X0500Y1400R090 S1      
327SN_EEPROM_WP     R1    -2          A10X+011737Y+007086X0280Y0240     S2      
327SN_EEPROM_WP     R344  -1          A10X+010800Y+007180X0280Y0240     S2      
327SN_EEPROM_WP     R1992 -2          A01X+011737Y+007536X0280Y0240R180 S1      
327SN_EEPROM_WP     U7    -5          A01X+010705Y+007284X0200Y0470R090 S1      
317SN_EEPROM_WP     VIA   -    MD0080PA00X+011288Y+007302X0180Y0180     S3      
317SEC_EEPROM_WP    VIA   -    MD0100PA00X+030750Y+016050X0200Y0200     S3      
327SEC_EEPROM_WP    J17   -3          A01X+034426Y+028650X0500Y1400R090 S1      
317SEC_EEPROM_WP    VIA   -    MD0080PA00X+033650Y+029500X0180Y0180     S3      
327SEC_EEPROM_WP    R24   -1          A10X+008470Y+007100X0280Y0240R180 S2      
317SEC_EEPROM_WP    TP20  -1   MD0100PA00X+007550Y+006200X0200Y0200     S2      
327SEC_EEPROM_WP    R2    -2   M      A10X+007990Y+007110X0280Y0240R090 S2      
327SEC_EEPROM_WP    R3    -2   M      A10X+008090Y+006650X0280Y0240     S2      
327SEC_EEPROM_WP    U19   -7          A01X+007878Y+007085X0620Y0140R270 S1      
327SEC_EEPROM_SDA   R45   -2          A10X+007210Y+008170X0280Y0240R090 S2      
317SEC_EEPROM_SDA   VIA   -    MD0100PA00X+007150Y+007700X0200Y0200R090 S3      
327SEC_EEPROM_SDA   U19   -5          A01X+007366Y+007085X0620Y0140R270 S1      
327R_FT_USB_DP      U18   -8          A01X+011328Y+035780X0120Y0640     S1      
327R_FT_USB_DP      R129  -2          A01X+011050Y+036890X0280Y0240R270 S1      
327R_FT_USB_DM      U18   -7          A01X+011525Y+035780X0120Y0640     S1      
327R_FT_USB_DM      R128  -2          A01X+011550Y+036890X0280Y0240R270 S1      
327R_FT4232_TMS     R470  -1          A10X+008690Y+034100X0280Y0240R180 S2      
317R_FT4232_TMS     VIA   -    MD0100PA00X+008300Y+034450X0200Y0200     S3      
327R_FT4232_TMS     U18   -19         A01X+008940Y+034573X0120Y0640R090 S1      
327R_FT4232_TDO     R466  -1          A10X+008690Y+034550X0280Y0240R180 S2      
327R_FT4232_TDO     R469  -1   M      A10X+008690Y+035000X0280Y0240R180 S2      
317R_FT4232_TDO     VIA   -    MD0100PA00X+007950Y+034850X0200Y0200     S3      
327R_FT4232_TDO     U18   -18         A01X+008940Y+034770X0120Y0640R090 S1      
327R_FT4232_TDI     R468  -1          A10X+008820Y+035530X0280Y0240R270 S2      
317R_FT4232_TDI     VIA   -    MD0100PA00X+008300Y+035250X0200Y0200     S3      
327R_FT4232_TDI     U18   -17         A01X+008940Y+034966X0120Y0640R090 S1      
327R_FT4232_TCK     R467  -1          A10X+009500Y+035640X0280Y0240R270 S2      
317R_FT4232_TCK     VIA   -    MD0100PA00X+009510Y+035190X0200Y0200     S3      
327R_FT4232_TCK     U18   -16         A01X+009754Y+035780X0120Y0640     S1      
317m0043            VIA   -    MD0100PA00X+008295Y+032794X0200Y0200     S3      
327m0043            U18   -27         A01X+008940Y+032998X0120Y0640R090 S1      
327m0043            R472  -1          A01X+007460Y+032000X0280Y0240R180 S1      
327m0044            R473  -1          A10X+007460Y+031550X0280Y0240     S2      
317m0044            VIA   -    MD0100PA00X+007900Y+031550X0200Y0200     S3      
327m0044            U18   -28         A01X+008940Y+032801X0120Y0640R090 S1      
317m0045            VIA   -    MD0100PA00X+007864Y+032449X0200Y0200     S3      
327m0045            U18   -26         A01X+008940Y+033195X0120Y0640R090 S1      
327m0045            R471  -1          A01X+007460Y+032450X0280Y0240R180 S1      
327m0046            R131  -1          A10X+012800Y+031360X0280Y0240R090 S2      
317m0046            VIA   -    MD0100PA00X+012600Y+031800X0200Y0200     S3      
327m0046            U18   -48         A01X+012706Y+031200X0120Y0640     S1      
327m0047            R349  -1          A10X+013390Y+032350X0280Y0240R180 S2      
327m0047            R132  -1   M      A10X+013390Y+032800X0280Y0240R180 S2      
317m0047            VIA   -    MD0100PA00X+012950Y+032800X0200Y0200     S3      
327m0047            U18   -52         A01X+013520Y+032604X0120Y0640R090 S1      
317m0048            VIA   -    MD0100PA00X+010750Y+030200X0200Y0200     S3      
327m0048            R353  -1          A01X+010750Y+029810X0280Y0240R270 S1      
327m0048            U18   -38         A01X+010738Y+031200X0120Y0640     S1      
317m0049            VIA   -    MD0100PA00X+011250Y+030200X0200Y0200     S3      
327m0049            R481  -1          A01X+011750Y+029810X0280Y0240R270 S1      
327m0049            R352  -1   M      A01X+011250Y+029810X0280Y0240R270 S1      
327m0049            U18   -39         A01X+010935Y+031200X0120Y0640     S1      
317FT_USB_DP        VIA   -    MD0080PA00X+010730Y+038250X0180Y0180     S3      
317FT_USB_DP        VIA   -    MD0080PA00X+007030Y+035750X0180Y0180     S3      
327FT_USB_DP        R129  -1          A01X+011050Y+037310X0280Y0240R270 S1      
317FT_USB_DP        J13   -A6  MD0160PA00X+003524Y+034315X0240Y0240R270 S3      
327FT_USB_DP        U17   -6   M      A01X+006826Y+035065X0200Y0470R180 S1      
317FT_USB_DP        J13   -B6   D0160PA00X+003347Y+034008X0240Y0240R270 S3      
317FT_USB_DM        VIA   -    MD0080PA00X+007350Y+035750X0180Y0180     S3      
317FT_USB_DM        VIA   -    MD0080PA00X+011050Y+038250X0180Y0180     S3      
327FT_USB_DM        R128  -1          A01X+011550Y+037310X0280Y0240R270 S1      
317FT_USB_DM        J13   -A7  MD0160PA00X+003878Y+034315X0240Y0240R270 S3      
317FT_USB_DM        J13   -B7   D0160PA00X+002992Y+034008X0240Y0240R270 S3      
327FT_USB_DM        U17   -4   M      A01X+007574Y+035065X0200Y0470R180 S1      
327FT_USB_DETECT    R456  -2          A01X+010550Y+036890X0280Y0240R270 S1      
327FT_USB_DETECT    R460  -1          A10X+010400Y+036060X0280Y0240R090 S2      
327FT_USB_DETECT    R18   -2          A10X+010550Y+036890X0280Y0240R090 S2      
317FT_USB_DETECT    TP11  -1   MD0100PA00X+009950Y+037000X0200Y0200     S2      
327FT_USB_DETECT    R130  -1   M      A10X+009950Y+036060X0280Y0240R090 S2      
317FT_USB_DETECT    VIA   -    MD0100PA00X+042850Y+034600X0200Y0200     S3      
327FT_USB_DETECT    R443  -1   M      A01X+043400Y+034960X0280Y0240R270 S1      
327FT_USB_DETECT    Q1    -1          A01X+043980Y+035315X0390Y0550     S1      
327FTDI_EE_DO       VIA   -    M      A10X+020500Y+033750X0300Y0300     S2      
327FTDI_EE_DO       R454  -2          A10X+021050Y+034090X0280Y0240R090 S2      
327FTDI_EE_DO       R444  -2   M      A10X+021040Y+033600X0280Y0240     S2      
327FTDI_EE_DO       U31   -4          A10X+019695Y+033880X0200Y0650R270 S2      
327FTDI_EE_DAT      R454  -1   M      A10X+021050Y+034510X0280Y0240R090 S2      
317FTDI_EE_DAT      VIA   -    MD0100PA00X+021500Y+034380X0200Y0200     S3      
327FTDI_EE_DAT      U31   -3          A10X+019695Y+034380X0200Y0650R270 S2      
327FTDI_EE_DAT      U18   -61         A01X+013520Y+034376X0120Y0640R090 S1      
327FTDI_EE_CS       U18   -63         A01X+013520Y+034770X0120Y0640R090 S1      
317FTDI_EE_CS       VIA   -    MD0100PA00X+020500Y+035380X0200Y0200     S3      
327FTDI_EE_CS       U31   -1          A10X+019695Y+035380X0200Y0650R270 S2      
327FTDI_EE_CS       R446  -2          A10X+021040Y+035500X0280Y0240     S2      
327FTDI_EE_CLK      U18   -62         A01X+013520Y+034573X0120Y0640R090 S1      
317FTDI_EE_CLK      VIA   -    MD0100PA00X+020500Y+034880X0200Y0200     S3      
327FTDI_EE_CLK      U31   -2          A10X+019695Y+034880X0200Y0650R270 S2      
327FTDI_EE_CLK      R447  -2          A10X+021040Y+035000X0280Y0240     S2      
327FT4232_VREGOUT   U18   -37         A01X+010541Y+031200X0120Y0640     S1      
317FT4232_VREGOUT   VIA   -    MD0100PA00X+012900Y+032150X0200Y0200     S3      
327FT4232_VREGOUT   U18   -49         A01X+013520Y+032014X0120Y0640R090 S1      
327FT4232_VREGOUT   C90   -1          A10X+010350Y+031360X0280Y0240R090 S2      
317FT4232_VREGOUT   VIA   -    MD0100PA00X+010541Y+031850X0200Y0200     S3      
327FT4232_VREGOUT   C96   -1          A10X+013340Y+035000X0280Y0240R180 S2      
317FT4232_VREGOUT   VIA   -    MD0100PA00X+013000Y+034966X0200Y0200     S3      
327FT4232_VREGOUT   U18   -64         A01X+013520Y+034966X0120Y0640R090 S1      
317FT4232_VREGOUT   VIA   -    MD0100PA00X+010402Y+034742X0200Y0200     S3      
327FT4232_VREGOUT   U18   -12         A01X+010541Y+035780X0120Y0640     S1      
317m0050            VIA   -    MD0100PA00X+042050Y+036600X0200Y0200     S3      
327m0050            U30   -12         A01X+042745Y+036622X0140Y0620R090 S1      
327m0050            R470  -2          A10X+009110Y+034100X0280Y0240R180 S2      
317m0050            VIA   -    MD0100PA00X+009750Y+034100X0200Y0200     S3      
317m0051            VIA   -    MD0100PA00X+042250Y+035450X0200Y0200     S3      
327m0051            U30   -9          A01X+042745Y+035854X0140Y0620R090 S1      
317m0051            VIA   -    MD0100PA00X+010150Y+034100X0200Y0200     S3      
327m0051            R469  -2          A10X+009110Y+035000X0280Y0240R180 S2      
317m0052            VIA   -    MD0100PA00X+039500Y+036000X0200Y0200     S3      
327m0052            U30   -7          A01X+040355Y+036110X0140Y0620R090 S1      
317m0052            VIA   -    MD0100PA00X+008350Y+036000X0200Y0200     S3      
327m0052            R468  -2          A10X+008820Y+035950X0280Y0240R270 S2      
317m0053            VIA   -    MD0100PA00X+039500Y+037000X0200Y0200     S3      
327m0053            U30   -4          A01X+040355Y+036878X0140Y0620R090 S1      
327m0053            R467  -2          A10X+009500Y+036060X0280Y0240R270 S2      
317m0053            VIA   -    MD0100PA00X+009150Y+035950X0200Y0200     S3      
317m0054            VIA   -    MD0100PA00X+041184Y+035362X0200Y0200     S3      
317m0054            VIA   -    MD0100PA00X+040850Y+031100X0200Y0200     S3      
327m0054            U38   -6          A01X+041695Y+031176X0140Y0620R090 S1      
327m0054            U30   -6          A01X+040355Y+036366X0140Y0620R090 S1      
317m0055            VIA   -    MD0100PA00X+045100Y+030650X0200Y0200     S3      
327m0055            U38   -10         A01X+044085Y+030920X0140Y0620R090 S1      
317m0055            VIA   -    MD0100PA00X+043338Y+036047X0200Y0200     S3      
327m0055            U30   -10         A01X+042745Y+036110X0140Y0620R090 S1      
317m0056            VIA   -    MD0100PA00X+043400Y+032800X0200Y0200     S3      
327m0056            U38   -13         A01X+044085Y+031688X0140Y0620R090 S1      
317m0056            VIA   -    MD0100PA00X+043350Y+036650X0200Y0200     S3      
327m0056            U30   -13         A01X+042745Y+036878X0140Y0620R090 S1      
317FT4232_SPI_CLK   VIA   -    MD0100PA00X+040900Y+037134X0200Y0200     S3      
327FT4232_SPI_CLK   U38   -3          A01X+041695Y+031944X0140Y0620R090 S1      
327FT4232_SPI_CLK   U30   -3          A01X+040355Y+037134X0140Y0620R090 S1      
317m0057            VIA   -    MD0100PA00X+033800Y+010250X0200Y0200     S3      
317m0057            VIA   -    MD0100PA00X+045850Y+008650X0200Y0200     S3      
327m0057            R486  -1          A01X+046940Y+009150X0280Y0240     S1      
327m0057            U18   -23         A01X+008940Y+033785X0120Y0640R090 S1      
317m0057            VIA   -    MD0100PA00X+006200Y+032350X0200Y0200     S3      
317m0058            VIA   -    MD0100PA00X+039250Y+032390X0200Y0200     S3      
327m0058            R462  -1          A01X+039730Y+032390X0280Y0240     S1      
317m0058            VIA   -    MD0100PA00X+008250Y+033900X0200Y0200     S3      
327m0058            U18   -22         A01X+008940Y+033982X0120Y0640R090 S1      
317m0059            VIA   -    MD0100PA00X+007950Y+034179X0200Y0200     S3      
327m0059            U18   -21         A01X+008940Y+034179X0120Y0640R090 S1      
317m0059            VIA   -    MD0100PA00X+037950Y+037580X0200Y0200     S3      
327m0059            R449  -2          A01X+038390Y+037580X0280Y0240R180 S1      
317FT4232_I2C_SDA   VIA   -    MD0100PA00X+036200Y+012800X0200Y0200     S3      
317FT4232_I2C_SDA   VIA   -    MD0100PA00X+051950Y+007550X0200Y0200     S3      
327FT4232_I2C_SDA   U37   -10         A01X+051245Y+007660X0140Y0620R090 S1      
317FT4232_I2C_SDA   VIA   -    MD0100PA00X+049600Y+008500X0200Y0200     S3      
327FT4232_I2C_SDA   U37   -3          A01X+048855Y+008684X0140Y0620R090 S1      
327FT4232_I2C_SDA   R472  -2          A01X+007040Y+032000X0280Y0240R180 S1      
317FT4232_I2C_SDA   VIA   -    MD0100PA00X+006600Y+031850X0200Y0200     S3      
327FT4232_I2C_SDA   R473  -2          A10X+007040Y+031550X0280Y0240     S2      
327FT4232_I2C_SDA   R479  -1   M      A10X+007040Y+032000X0280Y0240R180 S2      
317FT4232_I2C_SCL   VIA   -    MD0100PA00X+036200Y+012350X0200Y0200     S3      
317FT4232_I2C_SCL   VIA   -    MD0100PA00X+051950Y+008150X0200Y0200     S3      
327FT4232_I2C_SCL   U37   -13         A01X+051245Y+008428X0140Y0620R090 S1      
327FT4232_I2C_SCL   U37   -6          A01X+048855Y+007916X0140Y0620R090 S1      
317FT4232_I2C_SCL   VIA   -    MD0100PA00X+049370Y+007916X0200Y0200     S3      
327FT4232_I2C_SCL   R478  -1          A10X+007040Y+032450X0280Y0240R180 S2      
317FT4232_I2C_SCL   VIA   -    MD0100PA00X+006600Y+032350X0200Y0200     S3      
327FT4232_I2C_SCL   R471  -2          A01X+007040Y+032450X0280Y0240R180 S1      
317m0060            VIA   -    MD0100PA00X+042050Y+038100X0200Y0200     S3      
327m0060            U30   -14         A01X+042745Y+037134X0140Y0620R090 S1      
327m0060            J14   -5          A01X+057106Y+028210X0500Y1400R090 S1      
317m0060            VIA   -    MD0080PA00X+058140Y+028210X0180Y0180     S3      
327m0060            CR6   -2   M      A10X+056705Y+029225X0570Y0390R270 S2      
327m0060            R136  -1          A10X+055440Y+029225X0280Y0240     S2      
317m0061            VIA   -    MD0100PA00X+041900Y+037350X0200Y0200     S3      
327m0061            U30   -11         A01X+042745Y+036366X0140Y0620R090 S1      
327m0061            R135  -1          A10X+055460Y+027700X0280Y0240     S2      
327m0061            CR7   -3   M      A10X+056755Y+027245X0570Y0390R270 S2      
327m0061            J14   -3          A01X+057106Y+027210X0500Y1400R090 S1      
317m0061            VIA   -    MD0080PA00X+058140Y+027210X0180Y0180     S3      
317m0062            VIA   -    MD0100PA00X+038950Y+037000X0200Y0200     S3      
327m0062            U30   -5          A01X+040355Y+036622X0140Y0620R090 S1      
327m0062            R137  -1          A10X+055460Y+030200X0280Y0240     S2      
327m0062            CR6   -3   M      A10X+056705Y+030095X0570Y0390R270 S2      
327m0062            J14   -9          A01X+057106Y+030210X0500Y1400R090 S1      
317m0062            VIA   -    MD0080PA00X+058150Y+030210X0180Y0180     S3      
317m0063            VIA   -    MD0100PA00X+041350Y+037350X0200Y0200     S3      
327m0063            U30   -2          A01X+040355Y+037390X0140Y0620R090 S1      
327m0063            CR7   -2   M      A10X+056755Y+026375X0570Y0390R270 S2      
327m0063            R134  -1          A10X+055460Y+026400X0280Y0240     S2      
327m0063            J14   -1          A01X+057106Y+026210X0500Y1400R090 S1      
317m0063            VIA   -    MD0080PA00X+058140Y+026210X0180Y0180     S3      
317FT4232_CHD_TX    VIA   -    MD0100PA00X+023000Y+034750X0200Y0200     S3      
317FT4232_CHD_TX    VIA   -    MD0100PA00X+050450Y+034050X0200Y0200     S3      
327FT4232_CHD_TX    J10   -3          A01X+062236Y+027150X0500Y1400R090 S1      
317FT4232_CHD_TX    VIA   -    MD0080PA00X+063300Y+026700X0180Y0180     S3      
327FT4232_CHD_TX    J10   -1          A01X+062236Y+026150X0500Y1400R090 S1      
327FT4232_CHD_TX    R131  -2          A10X+012800Y+030940X0280Y0240R090 S2      
317FT4232_CHD_TX    VIA   -    MD0100PA00X+013500Y+031200X0200Y0200     S3      
317FT4232_CHD_RX    VIA   -    MD0100PA00X+022550Y+034750X0200Y0200     S3      
317FT4232_CHD_RX    VIA   -    MD0100PA00X+050900Y+034050X0200Y0200     S3      
327FT4232_CHD_RX    J10   -5          A01X+062236Y+028150X0500Y1400R090 S1      
317FT4232_CHD_RX    VIA   -    MD0100PA00X+063300Y+028650X0200Y0200     S3      
327FT4232_CHD_RX    J10   -7          A01X+062236Y+029150X0500Y1400R090 S1      
327FT4232_CHD_RX    R132  -2          A10X+013810Y+032800X0280Y0240R180 S2      
317FT4232_CHD_RX    VIA   -    MD0100PA00X+014600Y+033400X0200Y0200     S3      
317m0064            VIA   -    MD0100PA00X+045750Y+022350X0200Y0200     S3      
317m0064            VIA   -    MD0080PA00X+045018Y+019418X0180Y0180     S0      
327m0064            U24   -T16        A01X+044822Y+019222X0197Y0197R090 S1      
317m0064            VIA   -    MD0100PA00X+047050Y+008250X0200Y0200     S3      
327m0064            R474  -2   M      A01X+047360Y+008650X0280Y0240     S1      
327m0064            U37   -2          A01X+048855Y+008940X0140Y0620R090 S1      
317m0065            VIA   -    MD0100PA00X+045750Y+022750X0200Y0200     S3      
317m0065            VIA   -    MD0080PA00X+043837Y+019812X0180Y0180     S0      
327m0065            U24   -N17        A01X+043641Y+019615X0197Y0197R090 S1      
317m0065            VIA   -    MD0100PA00X+047550Y+008250X0200Y0200     S3      
327m0065            R475  -2   M      A01X+047360Y+007850X0280Y0240     S1      
327m0065            U37   -5          A01X+048855Y+008172X0140Y0620R090 S1      
317m0066            VIA   -    MD0100PA00X+012600Y+007200X0200Y0200     S3      
327m0066            R1    -1          A10X+012157Y+007086X0280Y0240     S2      
317m0066            VIA   -    MD0080PA00X+046987Y+018237X0180Y0180     S0      
327m0066            U24   -AA13       A01X+046790Y+018041X0197Y0197R090 S1      
317m0067            VIA   -    MD0100PA00X+008420Y+007500X0200Y0200R090 S3      
327m0067            R2    -1          A10X+007990Y+007530X0280Y0240R090 S2      
317m0067            VIA   -    MD0080PA00X+047381Y+018237X0180Y0180     S0      
327m0067            U24   -AB13       A01X+047184Y+018041X0197Y0197R090 S1      
317m0068            VIA   -    MD0080PA00X+041082Y+019025X0180Y0180     S2      
317m0068            VIA   -    MD0100PA00X+037365Y+018574X0200Y0200     S3      
327m0068            R485  -1          A01X+046940Y+009650X0280Y0240     S1      
327m0068            U24   -G15        A01X+041278Y+018828X0197Y0197R090 S1      
317m0069            VIA   -    MD0080PA00X+041082Y+018237X0180Y0180     S0      
317m0069            VIA   -    MD0100PA00X+043450Y+030200X0200Y0200     S3      
327m0069            U24   -G13        A01X+041278Y+018041X0197Y0197R090 S1      
317m0069            VIA   -    MD0100PA00X+040750Y+030050X0200Y0200     S3      
317m0069            VIA   -    MD0100PA00X+039250Y+032910X0200Y0200     S3      
327m0069            R461  -1          A01X+039730Y+032910X0280Y0240     S1      
317m0070            VIA   -    MD0080PA00X+041475Y+018237X0180Y0180     S0      
317m0070            VIA   -    MD0100PA00X+043900Y+030200X0200Y0200     S3      
327m0070            U24   -H13        A01X+041672Y+018041X0197Y0197R090 S1      
317m0070            VIA   -    MD0100PA00X+041300Y+030050X0200Y0200     S3      
317m0070            VIA   -    MD0100PA00X+037950Y+038100X0200Y0200     S3      
327m0070            R448  -2          A01X+038390Y+038100X0280Y0240R180 S1      
317m0071            VIA   -    MD0100PA00X+046150Y+031100X0200Y0200     S3      
317m0071            VIA   -    MD0080PA00X+046987Y+019025X0180Y0180     S0      
327m0071            U24   -AA15       A01X+046790Y+018828X0197Y0197R090 S1      
327m0071            R443  -2          A01X+043400Y+034540X0280Y0240R270 S1      
317m0071            VIA   -    MD0100PA00X+044000Y+033250X0200Y0200     S3      
317FPGA_IO_7        VIA   -    MD0100PA00X+046150Y+026841X0200Y0200     S3      
327FPGA_IO_7        U24   -L21        A01X+042853Y+021190X0197Y0197R090 S1      
327FPGA_IO_7        R328  -2          A10X+041500Y+025100X0280Y0240R090 S2      
317FPGA_IO_7        VIA   -    MD0100PA00X+041500Y+024680X0200Y0200     S3      
327FPGA_IO_7        R327  -2          A01X+041500Y+025100X0280Y0240R270 S1      
327FPGA_IO_7        R329  -1          A10X+061700Y+014340X0280Y0240R270 S2      
317FPGA_IO_7        VIA   -    MD0100PA00X+062200Y+014150X0200Y0200     S3      
317FPGA_IO_6        VIA   -    MD0100PA00X+046850Y+027000X0200Y0200     S3      
327FPGA_IO_6        R325  -2   M      A01X+042090Y+025100X0280Y0240R270 S1      
317FPGA_IO_6        VIA   -    MD0100PA00X+042090Y+024680X0200Y0200     S3      
327FPGA_IO_6        R326  -2          A10X+042090Y+025100X0280Y0240R090 S2      
317FPGA_IO_6        VIA   -    MD0080PA00X+043444Y+021387X0180Y0180     S0      
327FPGA_IO_6        U24   -M21        A01X+043247Y+021190X0197Y0197R090 S1      
317FPGA_IO_6        VIA   -    MD0100PA00X+062200Y+015160X0200Y0200     S3      
327FPGA_IO_6        R428  -1          A10X+061700Y+015340X0280Y0240R270 S2      
317FPGA_IO_5        VIA   -    MD0100PA00X+049750Y+022600X0200Y0200     S3      
327FPGA_IO_5        R308  -2          A01X+040930Y+025100X0280Y0240R270 S1      
317FPGA_IO_5        VIA   -    MD0100PA00X+040930Y+024680X0200Y0200     S3      
327FPGA_IO_5        R309  -2          A10X+040930Y+025100X0280Y0240R090 S2      
327FPGA_IO_5        U24   -K22        A01X+042460Y+021584X0197Y0197R090 S1      
327FPGA_IO_5        R429  -1          A10X+061700Y+016340X0280Y0240R270 S2      
317FPGA_IO_5        VIA   -    MD0100PA00X+062200Y+016200X0200Y0200     S3      
317FPGA_IO_4        VIA   -    MD0100PA00X+049250Y+022600X0200Y0200     S3      
327FPGA_IO_4        R292  -2          A01X+040370Y+025100X0280Y0240R270 S1      
317FPGA_IO_4        VIA   -    MD0100PA00X+040370Y+024680X0200Y0200     S3      
327FPGA_IO_4        R293  -2          A10X+040370Y+025100X0280Y0240R090 S2      
327FPGA_IO_4        U24   -K21        A01X+042460Y+021190X0197Y0197R090 S1      
327FPGA_IO_4        R430  -1          A10X+061550Y+018110X0280Y0240R090 S2      
317FPGA_IO_4        VIA   -    MD0100PA00X+062200Y+018150X0200Y0200     S3      
317FPGA_IO_3        VIA   -    MD0100PA00X+059200Y+014100X0200Y0200     S3      
327FPGA_IO_3        R431  -2          A10X+059800Y+014190X0280Y0240R090 S2      
317FPGA_IO_3        VIA   -    MD0100PA00X+050900Y+021550X0200Y0200     S3      
327FPGA_IO_3        R285  -2          A01X+038010Y+025100X0280Y0240R270 S1      
317FPGA_IO_3        VIA   -    MD0100PA00X+038010Y+024680X0200Y0200     S3      
327FPGA_IO_3        R286  -2          A10X+038010Y+025100X0280Y0240R090 S2      
317FPGA_IO_3        VIA   -    MD0080PA00X+041082Y+020993X0180Y0180     S0      
327FPGA_IO_3        U24   -G20        A01X+041278Y+020796X0197Y0197R090 S1      
327FPGA_IO_2        R432  -2          A10X+059800Y+015390X0280Y0240R090 S2      
317FPGA_IO_2        VIA   -    MD0100PA00X+059200Y+015150X0200Y0200     S3      
317FPGA_IO_2        VIA   -    MD0100PA00X+051350Y+021550X0200Y0200     S3      
317FPGA_IO_2        VIA   -    MD0100PA00X+038600Y+024680X0200Y0200     S3      
327FPGA_IO_2        R284  -2          A10X+038600Y+025100X0280Y0240R090 S2      
327FPGA_IO_2        R283  -2          A01X+038600Y+025100X0280Y0240R270 S1      
317FPGA_IO_2        VIA   -    MD0080PA00X+041475Y+020993X0180Y0180     S0      
327FPGA_IO_2        U24   -H20        A01X+041672Y+020796X0197Y0197R090 S1      
317FPGA_IO_1        VIA   -    MD0100PA00X+059200Y+016300X0200Y0200     S3      
327FPGA_IO_1        R433  -2          A10X+059800Y+016340X0280Y0240R090 S2      
317FPGA_IO_1        VIA   -    MD0100PA00X+051150Y+020650X0200Y0200     S3      
327FPGA_IO_1        R172  -2          A01X+039190Y+025100X0280Y0240R270 S1      
317FPGA_IO_1        VIA   -    MD0100PA00X+039190Y+024680X0200Y0200     S3      
327FPGA_IO_1        R173  -2          A10X+039190Y+025100X0280Y0240R090 S2      
327FPGA_IO_1        U24   -H22        A01X+041672Y+021584X0197Y0197R090 S1      
327FPGA_IO_0        R434  -2          A10X+059800Y+017390X0280Y0240R090 S2      
317FPGA_IO_0        VIA   -    MD0100PA00X+059200Y+017300X0200Y0200     S3      
317FPGA_IO_0        VIA   -    MD0100PA00X+051300Y+021050X0200Y0200     S3      
327FPGA_IO_0        U24   -J22        A01X+042066Y+021584X0197Y0197R090 S1      
327FPGA_IO_0        R170  -2          A01X+039780Y+025100X0280Y0240R270 S1      
317FPGA_IO_0        VIA   -    MD0100PA00X+039780Y+024680X0200Y0200     S3      
327FPGA_IO_0        R171  -2          A10X+039780Y+025100X0280Y0240R090 S2      
317FPGA_FLASH_DQ3   VIA   -    MD0100PA00X+046850Y+026450X0200Y0200     S3      
327FPGA_FLASH_DQ3   R348  -2          A01X+046200Y+024610X0280Y0240R090 S1      
317FPGA_FLASH_DQ3   VIA   -    MD0100PA00X+041000Y+033800X0200Y0200     S3      
327FPGA_FLASH_DQ3   U40   -4          A01X+041494Y+034076X0240Y0170R270 S1      
327FPGA_FLASH_DQ3   R465  -1          A01X+040800Y+034290X0280Y0240R090 S1      
327FPGA_FLASH_DQ2   R339  -2          A01X+045300Y+024610X0280Y0240R090 S1      
317FPGA_FLASH_DQ2   VIA   -    MD0100PA00X+045300Y+025000X0200Y0200     S3      
317FPGA_FLASH_DQ2   VIA   -    MD0100PA00X+039000Y+033850X0200Y0200     S3      
327FPGA_FLASH_DQ2   U39   -4          A01X+039544Y+034056X0240Y0170R270 S1      
327FPGA_FLASH_DQ2   R464  -1          A01X+038700Y+034240X0280Y0240R090 S1      
327m0072            R435  -1          A01X+045750Y+024190X0280Y0240R090 S1      
327m0072            U38   -11         A01X+044085Y+031176X0140Y0620R090 S1      
317m0072            VIA   -    MD0100PA00X+044850Y+031150X0200Y0200     S3      
327m0072            R238  -2          A01X+045350Y+023660X0280Y0240R090 S1      
317m0072            VIA   -    MD0100PA00X+045750Y+023740X0200Y0200     S3      
327m0073            R234  -2          A01X+044850Y+024610X0280Y0240R090 S1      
317m0073            VIA   -    MD0100PA00X+044850Y+025000X0200Y0200     S3      
317m0073            VIA   -    MD0100PA00X+042944Y+031008X0200Y0200     S3      
327m0073            U38   -5          A01X+041695Y+031432X0140Y0620R090 S1      
317m0074            VIA   -    MD0100PA00X+046100Y+023450X0200Y0200     S3      
327m0074            R362  -2          A01X+046500Y+023410X0280Y0240R090 S1      
327m0074            U38   -14         A01X+044085Y+031944X0140Y0620R090 S1      
317m0074            VIA   -    MD0100PA00X+045400Y+031250X0200Y0200     S3      
317FPGA_FLASH_CLK   VIA   -    MD0100PA00X+040850Y+032200X0200Y0200     S3      
327FPGA_FLASH_CLK   U38   -2          A01X+041695Y+032200X0140Y0620R090 S1      
327FPGA_FLASH_CLK   R207  -2          A10X+043500Y+024610X0280Y0240R270 S2      
317FPGA_FLASH_CLK   VIA   -    MD0100PA00X+043500Y+025050X0200Y0200     S3      
317m0075            VIA   -    MD0100PA00X+053650Y+007900X0200Y0200     S3      
327m0075            U37   -11         A01X+051245Y+007916X0140Y0620R090 S1      
327m0075            R476  -2   M      A01X+052490Y+007600X0280Y0240R180 S1      
327m0075            U24   -AB17       A01X+047184Y+019615X0197Y0197R090 S1      
317m0076            VIA   -    MD0100PA00X+053650Y+008450X0200Y0200     S3      
327m0076            R477  -2   M      A01X+052490Y+008200X0280Y0240R180 S1      
327m0076            U37   -14         A01X+051245Y+008684X0140Y0620R090 S1      
327m0076            U24   -AB16       A01X+047184Y+019222X0197Y0197R090 S1      
317FLASH_DQ3        VIA   -    MD0100PA00X+040661Y+035341X0200Y0200     S3      
327FLASH_DQ3        R206  -2          A10X+035060Y+032350X0280Y0240R180 S2      
327FLASH_DQ3        R465  -2   M      A01X+040800Y+034710X0280Y0240R090 S1      
327FLASH_DQ3        U40   -3          A01X+041494Y+034824X0240Y0170R270 S1      
327FLASH_DQ2        R205  -2          A10X+037440Y+034150X0280Y0240     S2      
317FLASH_DQ2        VIA   -    MD0080PA00X+038300Y+034660X0180Y0180     S3      
327FLASH_DQ2        R464  -2   M      A01X+038700Y+034660X0280Y0240R090 S1      
327FLASH_DQ2        U39   -3          A01X+039544Y+034804X0240Y0170R270 S1      
317FLASH_DQ1_MISO   VIA   -    MD0100PA00X+043514Y+030664X0200Y0200     S3      
327FLASH_DQ1_MISO   U38   -9          A01X+044085Y+030664X0140Y0620R090 S1      
317FLASH_DQ1_MISO   VIA   -    MD0100PA00X+037000Y+033250X0200Y0200     S3      
327FLASH_DQ1_MISO   R204  -2          A10X+037440Y+033250X0280Y0240     S2      
327FLASH_DQ0_MOSI   U38   -7          A01X+041695Y+030920X0140Y0620R090 S1      
317FLASH_DQ0_MOSI   VIA   -    MD0080PA00X+035825Y+034005X0180Y0180     S3      
327FLASH_DQ0_MOSI   R203  -2          A10X+035060Y+034150X0280Y0240R180 S2      
317FLASH_CS_N       VIA   -    MD0100PA00X+043300Y+031432X0200Y0200     S3      
327FLASH_CS_N       U38   -12         A01X+044085Y+031432X0140Y0620R090 S1      
327FLASH_CS_N       R191  -2          A10X+037860Y+032350X0280Y0240R180 S2      
317FLASH_CS_N       VIA   -    MD0100PA00X+038300Y+032350X0200Y0200     S3      
327FLASH_CS_N       U23   -1          A01X+037690Y+032350X0720Y0200R180 S1      
317FLASH_CLK        VIA   -    MD0100PA00X+040850Y+031650X0200Y0200     S3      
327FLASH_CLK        U38   -4          A01X+041695Y+031688X0140Y0620R090 S1      
327FLASH_CLK        R192  -1          A10X+034640Y+033250X0280Y0240R180 S2      
317FLASH_CLK        VIA   -    MD0080PA00X+034150Y+033350X0180Y0180     S3      
327FLASH_CLK        U23   -6          A01X+034810Y+033350X0720Y0200R180 S1      
327EEPROM_SDA       R312  -2          A01X+013085Y+006580X0280Y0240R180 S1      
327EEPROM_SDA       R183  -2   M      A01X+013085Y+006130X0280Y0240R180 S1      
327EEPROM_SDA       J9    -2          A01X+008050Y+014224X0500Y1400R180 S1      
317EEPROM_SDA       VIA   -    MD0100PA00X+007400Y+013000X0200Y0200     S3      
327EEPROM_SDA       R175  -2          A10X+013085Y+006580X0280Y0240     S2      
327EEPROM_SDA       R1991 -2          A10X+012158Y+006587X0280Y0240R180 S2      
327EEPROM_SDA       R345  -1          A01X+012157Y+006586X0280Y0240R180 S1      
317EEPROM_SDA       VIA   -    MD0080PA00X+012600Y+006200X0180Y0180     S3      
327EEPROM_SDA       R45   -1          A10X+007210Y+008590X0280Y0240R090 S2      
317EEPROM_SDA       VIA   -    MD0100PA00X+007850Y+008225X0200Y0200R090 S3      
327EEPROM_SCL       J9    -4          A01X+007050Y+014224X0500Y1400R180 S1      
317EEPROM_SCL       VIA   -    MD0100PA00X+006950Y+013000X0200Y0200     S3      
327EEPROM_SCL       U7    -1          A01X+009575Y+007284X0200Y0470R090 S1      
327EEPROM_SCL       R184  -2   M      A01X+013087Y+007080X0280Y0240R180 S1      
327EEPROM_SCL       R313  -2          A01X+013087Y+007530X0280Y0240R180 S1      
327EEPROM_SCL       R176  -2          A10X+013087Y+007080X0280Y0240     S2      
327EEPROM_SCL       R19   -2   M      A01X+011737Y+007086X0280Y0240R180 S1      
317EEPROM_SCL       VIA   -    MD0080PA00X+012600Y+006700X0180Y0180     S3      
317EEPROM_SCL       VIA   -    MD0100PA00X+007632Y+007830X0200Y0200R090 S3      
327EEPROM_SCL       U19   -6          A01X+007622Y+007085X0620Y0140R270 S1      
317BNO080_EVN_SDA   TP1   -1    D0100PA00X+033200Y+030150X0200Y0200R090 S2      
327BNO080_EVN_SDA   R341  -2   M      A10X+034850Y+028640X0280Y0240R090 S2      
327BNO080_EVN_SDA   R330  -2          A10X+034400Y+028640X0280Y0240R090 S2      
317BNO080_EVN_SCL   TP2   -1    D0100PA00X+032400Y+030100X0200Y0200R270 S2      
327BNO080_EVN_SCL   R342  -2   M      A10X+033950Y+029060X0280Y0240R270 S2      
327BNO080_EVN_SCL   R363  -2          A10X+033500Y+029060X0280Y0240R270 S2      
317m0077            VIA   -    MD0100PA00X+006060Y+015700X0200Y0200     S3      
327m0077            J9    -3          A01X+007050Y+016276X0500Y1400R180 S1      
327m0077            R59   -1          A10X+006740Y+014950X0280Y0240R180 S2      
317m0078            VIA   -    MD0100PA00X+008350Y+017300X0200Y0200     S3      
327m0078            R58   -1          A10X+008500Y+016840X0280Y0240     S2      
327m0078            J9    -1          A01X+008050Y+016276X0500Y1400R180 S1      
317m0079            VIA   -    MD0100PA00X+003550Y+032700X0200Y0200     S3      
327m0079            DS18  -4          A01X+000687Y+033041X0330Y0350R090 S1      
327m0079            R426  -2   M      A01X+003800Y+032310X0280Y0240R090 S1      
327m0079            R398  -2          A01X+004300Y+032310X0280Y0240R090 S1      
317m0080            VIA   -    MD0100PA00X+002800Y+032700X0200Y0200     S3      
327m0080            DS18  -3          A01X+000825Y+032687X0180Y0200R090 S1      
327m0080            R427  -2   M      A01X+002800Y+032310X0280Y0240R090 S1      
327m0080            R399  -2          A01X+003300Y+032310X0280Y0240R090 S1      
317m0081            VIA   -    MD0100PA00X+001300Y+031870X0200Y0200     S3      
327m0081            R425  -2          A01X+002300Y+032310X0280Y0240R090 S1      
327m0081            R397  -2   M      A01X+001800Y+032310X0280Y0240R090 S1      
327m0081            DS18  -1          A01X+000687Y+031998X0330Y0350R090 S1      
317m0082            VIA   -    MD0100PA00X+006902Y+019852X0200Y0200     S3      
327m0082            R401  -2   M      A01X+007455Y+019750X0280Y0240R180 S1      
327m0082            R395  -2          A01X+007455Y+019300X0280Y0240R180 S1      
317m0082            VIA   -    MD0100PA00X+001250Y+021950X0200Y0200     S3      
327m0082            DS17  -4          A01X+000687Y+021624X0330Y0350R090 S1      
317m0083            VIA   -    MD0100PA00X+006900Y+019300X0200Y0200     S3      
327m0083            R396  -2   M      A01X+007455Y+018850X0280Y0240R180 S1      
327m0083            R424  -2          A01X+007455Y+018400X0280Y0240R180 S1      
317m0083            VIA   -    MD0100PA00X+001250Y+021450X0200Y0200     S3      
327m0083            DS17  -3          A01X+000825Y+021270X0180Y0200R090 S1      
317m0084            VIA   -    MD0100PA00X+006900Y+018750X0200Y0200     S3      
327m0084            R400  -2   M      A01X+007455Y+017950X0280Y0240R180 S1      
327m0084            R394  -2          A01X+007455Y+017500X0280Y0240R180 S1      
317m0084            VIA   -    MD0100PA00X+001250Y+020450X0200Y0200     S3      
327m0084            DS17  -1          A01X+000687Y+020581X0330Y0350R090 S1      
317m0085            VIA   -    MD0100PA00X+001300Y+027333X0200Y0200     S3      
327m0085            R392  -2   M      A01X+003770Y+027061X0280Y0240R090 S1      
327m0085            R375  -2          A01X+004220Y+027061X0280Y0240R090 S1      
327m0085            DS16  -4          A01X+000687Y+027333X0330Y0350R090 S1      
317m0086            VIA   -    MD0100PA00X+002870Y+027430X0200Y0200     S3      
327m0086            R376  -2   M      A01X+002870Y+027061X0280Y0240R090 S1      
327m0086            R393  -2          A01X+003320Y+027061X0280Y0240R090 S1      
327m0086            DS16  -3          A01X+000825Y+026978X0180Y0200R090 S1      
317m0087            VIA   -    MD0100PA00X+001250Y+026150X0200Y0200     S3      
327m0087            R391  -2   M      A01X+001970Y+027061X0280Y0240R090 S1      
327m0087            R374  -2          A01X+002420Y+027061X0280Y0240R090 S1      
327m0087            DS16  -1          A01X+000687Y+026289X0330Y0350R090 S1      
317m0088            VIA   -    MD0100PA00X+007350Y+011900X0200Y0200     S3      
327m0088            R274  -2   M      A01X+007790Y+012500X0280Y0240R180 S1      
327m0088            R389  -2          A01X+007790Y+013000X0280Y0240R180 S1      
317m0088            VIA   -    MD0100PA00X+001250Y+010600X0200Y0200     S3      
327m0088            DS15  -4          A01X+000687Y+010207X0330Y0350R090 S1      
317m0089            VIA   -    MD0100PA00X+006800Y+011900X0200Y0200     S3      
327m0089            R390  -2          A01X+007790Y+012000X0280Y0240R180 S1      
327m0089            R373  -2   M      A01X+007790Y+011500X0280Y0240R180 S1      
317m0089            VIA   -    MD0100PA00X+001250Y+010100X0200Y0200     S3      
327m0089            DS15  -3          A01X+000825Y+009852X0180Y0200R090 S1      
317m0090            VIA   -    MD0100PA00X+006750Y+011450X0200Y0200     S3      
327m0090            R273  -2   M      A01X+007790Y+011000X0280Y0240R180 S1      
327m0090            R388  -2          A01X+007790Y+010500X0280Y0240R180 S1      
317m0090            VIA   -    MD0100PA00X+001250Y+009100X0200Y0200     S3      
327m0090            DS15  -1          A01X+000687Y+009163X0330Y0350R090 S1      
317m0091            VIA   -    MD0100PA00X+001250Y+016200X0200Y0200     S3      
327m0091            R125  -2   M      A01X+003710Y+015690X0280Y0240R090 S1      
327m0091            R386  -2          A01X+004160Y+015690X0280Y0240R090 S1      
327m0091            DS14  -4          A01X+000687Y+015915X0330Y0350R090 S1      
317m0092            VIA   -    MD0100PA00X+001300Y+015700X0200Y0200     S3      
327m0092            DS14  -3          A01X+000825Y+015561X0180Y0200R090 S1      
327m0092            R272  -2   M      A01X+002810Y+015690X0280Y0240R090 S1      
327m0092            R387  -2          A01X+003260Y+015690X0280Y0240R090 S1      
317m0093            VIA   -    MD0100PA00X+001362Y+014872X0200Y0200     S3      
327m0093            DS14  -1          A01X+000687Y+014872X0330Y0350R090 S1      
327m0093            R385  -2   M      A01X+001910Y+015690X0280Y0240R090 S1      
327m0093            R124  -2          A01X+002360Y+015690X0280Y0240R090 S1      
317VDD_PCA9546A     VIA   -    MD0100PA00X+029370Y+031730X0200Y0200     S3      
327VDD_PCA9546A     U4    -16         A01X+030425Y+032254X0140Y0620R270 S1      
327VDD_PCA9546A     C38   -1   M      A01X+029370Y+032060X0280Y0240R180 S1      
317VDD_PCA9546A     VIA   -    MD0100PA00X+030100Y+031700X0200Y0200     S3      
327VDD_PCA9546A     R61   -1   M      A10X+030260Y+032100X0280Y0240R180 S2      
327VDD_PCA9546A     R62   -1          A10X+030260Y+032600X0280Y0240R180 S2      
317m0094            VIA   -    MD0080PA00X+008960Y+024890X0180Y0180     S3      
327m0094            U32   -5          A01X+008594Y+024275X0180Y0600R180 S1      
327m0094            R314  -2          A10X+008960Y+024440X0280Y0240R270 S2      
327m0095            U33   -5          A01X+042391Y+040117X0490Y0120R180 S1      
317m0095            VIA   -    MD0080PA00X+043117Y+040117X0180Y0180R270 S3      
327m0095            R323  -1          A01X+043540Y+040150X0280Y0240     S1      
327m0096            U33   -2          A01X+042391Y+039526X0490Y0120R180 S1      
317m0096            VIA   -    MD0080PA00X+043190Y+039220X0180Y0180R270 S3      
327m0096            R324  -2          A01X+043540Y+039150X0280Y0240R180 S1      
317m0097            VIA   -    MD0100PA00X+045000Y+041150X0200Y0200     S3      
327m0097            R364  -1          A01X+043960Y+040650X0280Y0240R180 S1      
317m0097            VIA   -    MD0080PA00X+013150Y+029050X0180Y0180     S3      
317m0097            VIA   -    MD0080PA00X+029320Y+032950X0180Y0180     S3      
327m0097            R310  -1          A01X+028950Y+032590X0280Y0240     S1      
317m0097            VIA   -    MD0100PA00X+009150Y+014000X0200Y0200R090 S3      
317m0097            VIA   -    MD0080PA00X+014200Y+006954X0180Y0180     S3      
327m0097            R312  -1          A01X+013505Y+006580X0280Y0240R180 S1      
317m0098            VIA   -    MD0100PA00X+045000Y+041650X0200Y0200     S3      
327m0098            R366  -1          A01X+043960Y+041150X0280Y0240R180 S1      
317m0098            VIA   -    MD0080PA00X+013600Y+029050X0180Y0180     S3      
317m0098            VIA   -    MD0080PA00X+028960Y+033010X0180Y0180     S3      
327m0098            R311  -1          A01X+028960Y+033320X0280Y0240     S1      
317m0098            VIA   -    MD0100PA00X+009650Y+014000X0200Y0200     S3      
327m0098            R313  -1          A01X+013507Y+007530X0280Y0240R180 S1      
317m0098            VIA   -    MD0080PA00X+014207Y+007790X0180Y0180     S3      
327m0099            U24   -Y18        A01X+046396Y+020009X0197Y0197R090 S1      
317m0099            VIA   -    MD0080PA00X+046593Y+020206X0180Y0180     S2      
317m0099            VIA   -    MD0100PA00X+043300Y+035350X0200Y0200     S3      
327m0099            R319  -1          A10X+043960Y+038650X0280Y0240     S2      
327m0100            R321  -1          A10X+043960Y+040650X0280Y0240     S2      
317m0100            VIA   -    MD0080PA00X+044400Y+040650X0180Y0180R270 S3      
317m0100            VIA   -    MD0080PA00X+046200Y+020600X0180Y0180     S0      
317m0100            VIA   -    MD0080PA00X+043950Y+034150X0180Y0180     S3      
327m0100            U24   -W19        A01X+046003Y+020403X0197Y0197R090 S1      
327m0101            R322  -1          A10X+043960Y+041150X0280Y0240     S2      
317m0101            VIA   -    MD0080PA00X+044400Y+041150X0180Y0180R270 S3      
317m0101            VIA   -    MD0080PA00X+046200Y+020993X0180Y0180     S0      
317m0101            VIA   -    MD0080PA00X+044250Y+033609X0180Y0180     S3      
327m0101            U24   -W20        A01X+046003Y+020796X0197Y0197R090 S1      
317m0102            VIA   -    MD0080PA00X+006380Y+027400X0180Y0180     S3      
327m0102            U32   -3          A01X+008338Y+022465X0180Y0600R180 S1      
327m0102            R316  -2          A10X+008050Y+024020X0280Y0240R090 S2      
317m0102            VIA   -    MD0080PA00X+008250Y+023050X0180Y0180     S3      
327m0102            R72   -1          A01X+006425Y+026640X0280Y0240     S1      
327m0102            R70   -2   M      A01X+006425Y+027090X0280Y0240R180 S1      
327m0103            R71   -2          A01X+008065Y+028310X0280Y0240R090 S1      
327m0103            R73   -1          A01X+007560Y+027900X0280Y0240R180 S1      
317m0103            VIA   -    MD0080PA00X+007550Y+028250X0180Y0180     S3      
327m0103            R315  -2          A10X+007600Y+024020X0280Y0240R090 S2      
317m0103            VIA   -    MD0080PA00X+007950Y+023450X0180Y0180     S3      
327m0103            U32   -2          A01X+008082Y+022465X0180Y0600R180 S1      
327m0104            R119  -1          A10X+060250Y+041310X0280Y0240R090 S2      
317m0104            VIA   -    MD0100PA00X+059761Y+041378X0200Y0200     S3      
327m0104            DS20  -A          A01X+060256Y+041378X0310Y0310R270 S1      
327m0105            R118  -1          A10X+059100Y+041310X0280Y0240R090 S2      
317m0105            VIA   -    MD0100PA00X+059075Y+041872X0200Y0200R270 S3      
327m0105            DS19  -A          A01X+059075Y+041378X0310Y0310R270 S1      
327m0106            R424  -1          A01X+007875Y+018400X0280Y0240R180 S1      
317m0106            VIA   -    MD0080PA00X+040688Y+020206X0180Y0180     S0      
317m0106            VIA   -    MD0100PA00X+009050Y+019350X0200Y0200     S3      
327m0106            U24   -F18        A01X+040885Y+020009X0197Y0197R090 S1      
317m0107            VIA   -    MD0080PA00X+039900Y+020600X0180Y0180     S0      
317m0107            VIA   -    MD0100PA00X+009450Y+019700X0200Y0200     S3      
327m0107            U24   -D19        A01X+040097Y+020403X0197Y0197R090 S1      
327m0107            R401  -1          A01X+007875Y+019750X0280Y0240R180 S1      
317m0108            VIA   -    MD0080PA00X+040294Y+020600X0180Y0180     S0      
317m0108            VIA   -    MD0100PA00X+009050Y+018850X0200Y0200     S3      
327m0108            U24   -E19        A01X+040491Y+020403X0197Y0197R090 S1      
327m0108            R400  -1          A01X+007875Y+017950X0280Y0240R180 S1      
317m0109            VIA   -    MD0100PA00X+006300Y+021500X0200Y0200     S3      
317m0109            VIA   -    MD0080PA00X+039507Y+020206X0180Y0180     S0      
317m0109            VIA   -    MD0100PA00X+009850Y+021850X0200Y0200     S3      
327m0109            U24   -C18        A01X+039704Y+020009X0197Y0197R090 S1      
317m0109            VIA   -    MD0100PA00X+002870Y+026251X0200Y0200     S3      
327m0109            R376  -1          A01X+002870Y+026641X0280Y0240R090 S1      
317m0110            VIA   -    MD0100PA00X+004300Y+025550X0200Y0200     S3      
327m0110            R375  -1          A01X+004220Y+026641X0280Y0240R090 S1      
317m0110            VIA   -    MD0080PA00X+039507Y+019812X0180Y0180     S0      
317m0110            VIA   -    MD0100PA00X+006300Y+021050X0200Y0200     S3      
317m0110            VIA   -    MD0100PA00X+009900Y+020150X0200Y0200     S3      
327m0110            U24   -C17        A01X+039704Y+019615X0197Y0197R090 S1      
317m0111            VIA   -    MD0100PA00X+002420Y+026251X0200Y0200     S3      
327m0111            R374  -1          A01X+002420Y+026641X0280Y0240R090 S1      
317m0111            VIA   -    MD0080PA00X+039900Y+019812X0180Y0180     S0      
317m0111            VIA   -    MD0100PA00X+006300Y+020600X0200Y0200     S3      
317m0111            VIA   -    MD0100PA00X+009900Y+019750X0200Y0200     S3      
327m0111            U24   -D17        A01X+040097Y+019615X0197Y0197R090 S1      
317m0112            VIA   -    MD0080PA00X+040294Y+018237X0180Y0180     S0      
317m0112            VIA   -    MD0100PA00X+009350Y+013000X0200Y0200     S3      
327m0112            R373  -1          A01X+008210Y+011500X0280Y0240R180 S1      
327m0112            U24   -E13        A01X+040491Y+018041X0197Y0197R090 S1      
317m0113            VIA   -    MD0080PA00X+039507Y+019025X0180Y0180     S0      
317m0113            VIA   -    MD0100PA00X+008700Y+012550X0200Y0200     S3      
327m0113            R274  -1          A01X+008210Y+012500X0280Y0240R180 S1      
327m0113            U24   -C15        A01X+039704Y+018828X0197Y0197R090 S1      
317m0114            VIA   -    MD0080PA00X+039507Y+018631X0180Y0180     S0      
317m0114            VIA   -    MD0100PA00X+009350Y+012500X0200Y0200     S3      
327m0114            R273  -1          A01X+008210Y+011000X0280Y0240R180 S1      
327m0114            U24   -C14        A01X+039704Y+018434X0197Y0197R090 S1      
317m0115            VIA   -    MD0080PA00X+040688Y+019418X0180Y0180     S0      
317m0115            VIA   -    MD0100PA00X+009200Y+017300X0200Y0200     S3      
327m0115            U24   -F16        A01X+040885Y+019222X0197Y0197R090 S1      
317m0115            VIA   -    MD0100PA00X+002810Y+014880X0200Y0200     S3      
327m0115            R272  -1          A01X+002810Y+015270X0280Y0240R090 S1      
317m0116            VIA   -    MD0080PA00X+040688Y+018631X0180Y0180     S0      
317m0116            VIA   -    MD0100PA00X+009850Y+016550X0200Y0200     S3      
327m0116            U24   -F14        A01X+040885Y+018434X0197Y0197R090 S1      
327m0116            R125  -1          A01X+003710Y+015270X0280Y0240R090 S1      
317m0116            VIA   -    MD0100PA00X+003710Y+014880X0200Y0200     S3      
317m0117            VIA   -    MD0080PA00X+040688Y+018237X0180Y0180     S0      
327m0117            U24   -F13        A01X+040885Y+018041X0197Y0197R090 S1      
317m0117            VIA   -    MD0100PA00X+009850Y+015900X0200Y0200     S3      
327m0117            R124  -1          A01X+002360Y+015270X0280Y0240R090 S1      
317m0117            VIA   -    MD0100PA00X+002360Y+014880X0200Y0200     S3      
327m0118            R427  -1          A01X+002800Y+031890X0280Y0240R090 S1      
317m0118            VIA   -    MD0100PA00X+003450Y+030900X0200Y0200     S3      
317m0118            VIA   -    MD0100PA00X+038409Y+020009X0200Y0200     S3      
327m0118            U24   -A18        A01X+038916Y+020009X0197Y0197R090 S1      
317m0118            VIA   -    MD0100PA00X+009900Y+018850X0200Y0200     S3      
327m0119            R426  -1          A01X+003800Y+031890X0280Y0240R090 S1      
317m0119            VIA   -    MD0100PA00X+003950Y+030900X0200Y0200     S3      
317m0119            VIA   -    MD0080PA00X+038719Y+020993X0180Y0180     S2      
327m0119            U24   -A20        A01X+038916Y+020796X0197Y0197R090 S1      
317m0119            VIA   -    MD0100PA00X+009900Y+020650X0200Y0200     S3      
327m0120            R425  -1          A01X+002300Y+031890X0280Y0240R090 S1      
317m0120            VIA   -    MD0100PA00X+004450Y+030900X0200Y0200     S3      
317m0120            VIA   -    MD0080PA00X+039113Y+020993X0180Y0180     S0      
317m0120            VIA   -    MD0100PA00X+009750Y+021400X0200Y0200     S3      
327m0120            U24   -B20        A01X+039310Y+020796X0197Y0197R090 S1      
327m0121            R495  -2          A10X+005300Y+020490X0280Y0240R090 S2      
327m0121            U16   -2          A01X+005571Y+019209X0380Y0120R270 S1      
317m0121            VIA   -    MD0100PA00X+005300Y+020050X0200Y0200     S3      
327m0121            R121  -2          A01X+005300Y+020490X0280Y0240R270 S1      
327m0122            R494  -2          A10X+005300Y+025840X0280Y0240R090 S2      
317m0122            VIA   -    MD0100PA00X+005520Y+025350X0200Y0200     S3      
327m0122            U15   -2          A01X+005571Y+024917X0380Y0120R270 S1      
327m0122            R120  -2          A01X+005300Y+025840X0280Y0240R270 S1      
317m0123            VIA   -    MD0100PA00X+004550Y+018250X0200Y0200     S3      
327m0123            R126  -2          A01X+004550Y+017810X0280Y0240R090 S1      
317m0123            J4    -1    D0590PA00X+001604Y+018543X0860Y0860     S3      
327m0123            CR4   -2   M      A01X+002725Y+020965X0570Y0390R090 S1      
317m0124            VIA   -    MD0100PA00X+004600Y+021950X0200Y0200     S3      
327m0124            R127  -2          A01X+004645Y+022330X0280Y0240R270 S1      
317m0124            J3    -1    D0590PA00X+001604Y+024252X0860Y0860     S3      
327m0124            CR4   -3   M      A01X+002725Y+021835X0570Y0390R090 S1      
317m0125            VIA   -    MD0100PA00X+004450Y+007350X0200Y0200     S3      
327m0125            R123  -2          A10X+005300Y+006970X0280Y0240R270 S2      
317m0125            J2    -1    D0590PA00X+001604Y+007126X0860Y0860     S3      
327m0125            CR5   -2   M      A01X+002725Y+009565X0570Y0390R090 S1      
327m0126            R122  -2          A01X+004550Y+010839X0280Y0240R270 S1      
317m0126            VIA   -    MD0100PA00X+004550Y+010439X0200Y0200     S3      
317m0126            J1    -1    D0590PA00X+001604Y+012835X0860Y0860     S3      
327m0126            CR5   -3   M      A01X+002725Y+010435X0570Y0390R090 S1      
317m0127            VIA   -    MD0100PA00X+005350Y+018350X0200Y0200     S3      
327m0127            R126  -1   M      A01X+004550Y+017390X0280Y0240R090 S1      
327m0127            R499  -2          A01X+004550Y+016860X0280Y0240R090 S1      
327m0127            U16   -5   M      A01X+005177Y+017878X0380Y0120R270 S1      
327m0127            U16   -6          A01X+005374Y+017878X0380Y0120R270 S1      
317m0128            VIA   -    MD0100PA00X+005320Y+024019X0200Y0200     S3      
327m0128            R127  -1          A01X+004645Y+022750X0280Y0240R270 S1      
327m0128            U15   -5   M      A01X+005177Y+023587X0380Y0120R270 S1      
327m0128            U15   -6          A01X+005374Y+023587X0380Y0120R270 S1      
327m0128            R498  -2   M      A01X+004520Y+023260X0280Y0240R270 S1      
327m0129            R123  -1          A10X+005300Y+006550X0280Y0240R270 S2      
317m0129            VIA   -    MD0100PA00X+005050Y+006023X0200Y0200     S3      
327m0129            U14   -6          A01X+005374Y+006461X0380Y0120R270 S1      
327m0129            U14   -5   M      A01X+005177Y+006461X0380Y0120R270 S1      
327m0129            R497  -2          A01X+004430Y+006470X0280Y0240R270 S1      
317m0130            VIA   -    MD0100PA00X+005374Y+012600X0200Y0200     S3      
327m0130            U13   -6          A01X+005374Y+012169X0380Y0120R270 S1      
327m0130            U13   -5   M      A01X+005177Y+012169X0380Y0120R270 S1      
327m0130            R496  -2   M      A01X+004550Y+011780X0280Y0240R270 S1      
327m0130            R122  -1          A01X+004550Y+011259X0280Y0240R270 S1      
317BF_ANT2_IN       VIA   -    MD0100PA00X+004800Y+020050X0200Y0200     S3      
327BF_ANT2_IN       U16   -3          A01X+005374Y+019209X0380Y0120R270 S1      
327BF_ANT2_IN       R372  -1          A01X+004800Y+020490X0280Y0240R090 S1      
317BF_ANT1_IN       VIA   -    MD0100PA00X+004850Y+025250X0200Y0200     S3      
327BF_ANT1_IN       U15   -3          A01X+005374Y+024917X0380Y0120R270 S1      
327BF_ANT1_IN       R371  -1          A01X+004780Y+025690X0280Y0240R090 S1      
317BF_ANT4_IN       VIA   -    MD0100PA00X+005150Y+008350X0200Y0200     S3      
327BF_ANT4_IN       R370  -1          A01X+004850Y+008840X0280Y0240R090 S1      
327BF_ANT4_IN       U14   -3          A01X+005374Y+007791X0380Y0120R270 S1      
317BF_ANT3_IN       VIA   -    MD0100PA00X+004750Y+014050X0200Y0200     S3      
327BF_ANT3_IN       R367  -1          A01X+004800Y+014440X0280Y0240R090 S1      
327BF_ANT3_IN       U13   -3          A01X+005374Y+013500X0380Y0120R270 S1      
327m0131            U36   -5          A01X+062655Y+010066X0180Y0600R090 S1      
327m0131            R411  -1          A10X+063790Y+009650X0280Y0240R180 S2      
317m0131            VIA   -    MD0100PA00X+063350Y+009650X0200Y0200     S3      
327m0131            R410  -2          A01X+063790Y+009650X0280Y0240R180 S1      
327m0132            U36   -6          A01X+062655Y+010322X0180Y0600R090 S1      
327m0132            R415  -1          A10X+063790Y+010200X0280Y0240R180 S2      
317m0132            VIA   -    MD0100PA00X+063350Y+010200X0200Y0200     S3      
327m0132            R414  -2          A01X+063790Y+010200X0280Y0240R180 S1      
327m0133            R419  -2          A01X+063790Y+010800X0280Y0240R180 S1      
327m0133            R417  -1          A10X+063790Y+010800X0280Y0240R180 S2      
327m0133            U36   -7          A01X+062655Y+010578X0180Y0600R090 S1      
317m0133            VIA   -    MD0100PA00X+063350Y+010800X0200Y0200     S3      
327m0134            U35   -5          A01X+020966Y+030845X0180Y0600     S1      
317m0134            VIA   -    MD0080PA00X+020850Y+030170X0180Y0180R270 S3      
327m0134            R408  -2          A01X+020830Y+029730X0280Y0240R090 S1      
327m0134            R409  -1          A10X+020830Y+029730X0280Y0240R090 S2      
327m0135            U35   -6          A01X+021222Y+030845X0180Y0600     S1      
317m0135            VIA   -    MD0080PA00X+021350Y+030170X0180Y0180R270 S3      
327m0135            R412  -2          A01X+021280Y+029730X0280Y0240R090 S1      
327m0135            R413  -1          A10X+021280Y+029730X0280Y0240R090 S2      
327m0136            U35   -7          A01X+021478Y+030845X0180Y0600     S1      
317m0136            VIA   -    MD0080PA00X+021850Y+030170X0180Y0180R270 S3      
327m0136            R418  -2          A01X+021730Y+029730X0280Y0240R090 S1      
327m0136            R416  -1          A10X+021730Y+029730X0280Y0240R090 S2      
327m0137            Q3    -1   M      A10X+029715Y+022780X0390Y0550R270 S2      
327m0137            Q2    -3          A10X+029665Y+021800X0390Y0550R090 S2      
327m0137            VIA   -    M      A10X+029250Y+022285X0300Y0300     S2      
327m0137            R44   -2          A10X+029100Y+022990X0280Y0240R090 S2      
327m0138            Q3    -3          A10X+030585Y+023150X0390Y0550R270 S2      
327m0138            VIA   -    M      A10X+029500Y+021300X0300Y0300     S2      
327m0138            FU3   -1   M      A10X+028450Y+022220X0300Y0340R090 S2      
327m0138            R357  -2          A10X+028500Y+022770X0380Y0540R090 S2      
327m0139            R407  -2          A01X+059560Y+010800X0280Y0240     S1      
317m0139            VIA   -    MD0100PA00X+060085Y+011235X0200Y0200     S3      
327m0139            U36   -1          A01X+060845Y+010834X0180Y0600R090 S1      
327m0140            U35   -1          A01X+021734Y+032655X0180Y0600     S1      
327m0140            R406  -2          A01X+022628Y+032870X0280Y0240R090 S1      
317m0140            VIA   -    MD0080PA00X+022200Y+033000X0180Y0180R270 S3      
327m0141            R423  -2   M      A01X+059560Y+009650X0280Y0240     S1      
317m0141            TP22  -1   MD0100PA00X+058000Y+010480X0200Y0200     S2      
327m0141            U36   -3          A01X+060845Y+010322X0180Y0600R090 S1      
317m0141            VIA   -    MD0080PA00X+043444Y+020206X0180Y0180     S0      
327m0141            U24   -M18        A01X+043247Y+020009X0197Y0197R090 S1      
317m0141            VIA   -    MD0080PA00X+052850Y+029900X0180Y0180     S3      
327m0142            U24   -M22        A01X+043247Y+021584X0197Y0197R090 S1      
317m0142            VIA   -    MD0100PA00X+031250Y+030750X0200Y0200     S3      
317m0142            VIA   -    MD0080PA00X+043444Y+021781X0180Y0180     S0      
327m0142            R422  -2          A01X+019590Y+032470X0280Y0240R270 S1      
327m0142            U35   -3          A01X+021222Y+032655X0180Y0600     S1      
317m0142            TP23  -1   MD0100PA00X+020170Y+032790X0200Y0200R270 S2      
317m0143            TP24  -1   MD0100PA00X+006360Y+029150X0200Y0200     S2      
327m0143            U8    -3          A10X+005505Y+029772X0180Y0600R270 S2      
327m0143            R340  -2   M      A10X+006990Y+029150X0280Y0240     S2      
317m0143            VIA   -    MD0080PA00X+043837Y+021781X0180Y0180     S0      
317m0143            VIA   -    MD0100PA00X+029700Y+031050X0200Y0200     S3      
327m0143            U24   -N22        A01X+043641Y+021584X0197Y0197R090 S1      
327m0144            J10   -6          A01X+060184Y+028150X0500Y1400R090 S1      
317m0144            VIA   -    MD0100PA00X+059100Y+027850X0200Y0200     S3      
327m0144            R82   -2          A10X+059940Y+027900X0280Y0240     S2      
327m0145            R81   -2          A10X+059940Y+026150X0280Y0240     S2      
327m0145            J10   -2          A01X+060184Y+026150X0500Y1400R090 S1      
317m0145            VIA   -    MD0080PA00X+059100Y+026150X0180Y0180     S3      
327m0146            R112  -1          A01X+049850Y+035040X0280Y0240R090 S1      
317m0146            VIA   -    MD0100PA00X+059100Y+029150X0200Y0200     S3      
327m0146            J10   -8          A01X+060184Y+029150X0500Y1400R090 S1      
327m0147            R113  -1          A01X+048850Y+035040X0280Y0240R090 S1      
317m0147            VIA   -    MD0100PA00X+059100Y+027150X0200Y0200     S3      
327m0147            J10   -4          A01X+060184Y+027150X0500Y1400R090 S1      
317ANT2_OUT         VIA   -    MD0100PA00X+005400Y+021350X0200Y0200     S3      
327ANT2_OUT         R121  -1          A01X+005300Y+020910X0280Y0240R270 S1      
317ANT2_OUT         VIA   -    MD0100PA00X+006700Y+010900X0200Y0200     S3      
317ANT2_OUT         VIA   -    MD0080PA00X+046200Y+016663X0180Y0180     S0      
327ANT2_OUT         U24   -W10        A01X+046003Y+016860X0197Y0197R090 S1      
327ANT2_IN          R503  -1          A10X+046790Y+020796X0250Y0250R180 S2      
327ANT2_IN          R372  -2          A01X+004800Y+020910X0280Y0240R090 S1      
317ANT2_IN          VIA   -    MD0100PA00X+004500Y+021300X0200Y0200     S3      
317ANT2_IN          VIA   -    MD0080PA00X+046987Y+020993X0180Y0180     S0      
327ANT2_IN          U24   -AA20       A01X+046790Y+020796X0197Y0197R090 S1      
317ANT2_IN          VIA   -    MD0100PA00X+009650Y+023550X0200Y0200     S3      
327ANT1_OUT         U24   -V10        A01X+045609Y+016860X0197Y0197R090 S1      
317ANT1_OUT         VIA   -    MD0080PA00X+045806Y+017056X0180Y0180     S0      
317ANT1_OUT         VIA   -    MD0100PA00X+007350Y+011250X0200Y0200     S3      
317ANT1_OUT         VIA   -    MD0100PA00X+004823Y+026453X0200Y0200     S3      
327ANT1_OUT         R120  -1          A01X+005300Y+026260X0280Y0240R270 S1      
327ANT1_IN          R504  -1          A10X+047184Y+021190X0250Y0250R270 S2      
327ANT1_IN          VIA   -    M      A10X+010050Y+028473X0300Y0300     S2      
317ANT1_IN          VIA   -    MD0080PA00X+037550Y+035050X0180Y0180R180 S3      
327ANT1_IN          U24   -AA21       A01X+046790Y+021190X0197Y0197R090 S1      
317ANT1_IN          VIA   -    MD0080PA00X+046987Y+021387X0180Y0180     S0      
317ANT1_IN          VIA   -    MD0100PA00X+005250Y+027800X0200Y0200     S3      
327ANT1_IN          R371  -2          A01X+004780Y+026110X0280Y0240R090 S1      
317ANT4_OUT         VIA   -    MD0100PA00X+046000Y+007600X0200Y0200     S3      
327ANT4_OUT         U24   -W12        A01X+046003Y+017647X0197Y0197R090 S1      
317ANT4_OUT         VIA   -    MD0080PA00X+046200Y+017844X0180Y0180     S0      
317ANT4_OUT         VIA   -    MD0100PA00X+009050Y+010500X0200Y0200     S3      
317ANT4_OUT         VIA   -    MD0100PA00X+041750Y+007500X0200Y0200     S3      
317ANT4_OUT         VIA   -    MD0080PA00X+005176Y+009660X0180Y0180R180 S3      
327ANT4_OUT         R157  -1          A01X+005350Y+009260X0280Y0240R270 S1      
317ANT4_IN          VIA   -    MD0100PA00X+020780Y+008301X0200Y0200     S3      
327ANT4_IN          R501  -2          A10X+046390Y+017550X0280Y0240     S2      
327ANT4_IN          R370  -2          A01X+004850Y+009260X0280Y0240R090 S1      
317ANT4_IN          VIA   -    MD0080PA00X+004600Y+008200X0180Y0180R180 S3      
317ANT4_IN          VIA   -    MD0080PA00X+046593Y+017844X0180Y0180     S0      
327ANT4_IN          U24   -Y12        A01X+046396Y+017647X0197Y0197R090 S1      
327ANT3_OUT         R156  -1          A01X+005300Y+014860X0280Y0240R270 S1      
317ANT3_OUT         VIA   -    MD0100PA00X+005413Y+015250X0200Y0200     S3      
317ANT3_OUT         VIA   -    MD0080PA00X+046200Y+017056X0180Y0180     S0      
327ANT3_OUT         U24   -W11        A01X+046003Y+017253X0197Y0197R090 S1      
317ANT3_OUT         VIA   -    MD0100PA00X+006250Y+010050X0200Y0200     S3      
327ANT3_IN          R500  -2          A10X+046790Y+016860X0250Y0250     S2      
317ANT3_IN          VIA   -    MD0080PA00X+046593Y+017056X0180Y0180     S0      
327ANT3_IN          U24   -Y11        A01X+046396Y+017253X0197Y0197R090 S1      
317ANT3_IN          VIA   -    MD0100PA00X+009350Y+011050X0200Y0200     S3      
327ANT3_IN          R367  -2          A01X+004800Y+014860X0280Y0240R090 S1      
317ANT3_IN          VIA   -    MD0100PA00X+004839Y+012831X0200Y0200     S3      
317PRI_EEPROM_SDA   VIA   -    MD0080PA00X+011280Y+006660X0180Y0180R180 S3      
327PRI_EEPROM_SDA   U7    -3          A01X+009575Y+006536X0200Y0470R090 S1      
327PRI_EEPROM_SDA   R345  -2          A01X+011737Y+006586X0280Y0240R180 S1      
327m0148            R279  -1          A10X+060270Y+042610X0280Y0240R090 S2      
317m0148            VIA   -    MD0100PA00X+059761Y+042756X0200Y0200     S3      
327m0148            DS10  -A          A01X+060256Y+042756X0310Y0310R270 S1      
327m0149            U24   -H14        A01X+041672Y+018434X0197Y0197R090 S1      
317m0149            VIA   -    MD0080PA00X+041475Y+018631X0180Y0180     S0      
317m0149            VIA   -    MD0100PA00X+009450Y+016300X0200Y0200     S3      
317m0149            TP35  -1   MD0100PA00X+006350Y+008450X0200Y0200     S2      
327m0149            R368  -2   M      A01X+005800Y+008840X0280Y0240R270 S1      
327m0149            U14   -1          A01X+005768Y+007791X0380Y0120R270 S1      
327m0150            U24   -J14        A01X+042066Y+018434X0197Y0197R090 S1      
317m0150            VIA   -    MD0080PA00X+041869Y+018631X0180Y0180     S0      
317m0150            VIA   -    MD0100PA00X+009750Y+017200X0200Y0200     S3      
317m0150            TP31  -1   MD0100PA00X+006440Y+007000X0200Y0200     S2      
327m0150            U14   -7          A01X+005571Y+006461X0380Y0120R270 S1      
317m0150            VIA   -    MD0100PA00X+005550Y+005900X0200Y0200     S3      
327m0150            R379  -2   M      A10X+005770Y+006550X0280Y0240R090 S2      
327SMA4_LED_RED_N   U33   -20         A01X+040489Y+039526X0490Y0120R180 S1      
317SMA4_LED_RED_N   VIA   -    MD0080PA00X+039350Y+039100X0180Y0180R090 S3      
317SMA4_LED_RED_N   VIA   -    MD0100PA00X+008350Y+018850X0200Y0200     S3      
327SMA4_LED_RED_N   R396  -1          A01X+007875Y+018850X0280Y0240R180 S1      
327m0151            U33   -19         A01X+040489Y+039723X0490Y0120R180 S1      
317m0151            VIA   -    MD0080PA00X+038850Y+039100X0180Y0180R090 S3      
317m0151            VIA   -    MD0100PA00X+008350Y+019300X0200Y0200     S3      
327m0151            R395  -1          A01X+007875Y+019300X0280Y0240R180 S1      
327m0152            U33   -21         A01X+040474Y+039329X0460Y0120R180 S1      
317m0152            VIA   -    MD0080PA00X+039850Y+039100X0180Y0180     S3      
317m0152            VIA   -    MD0100PA00X+008350Y+017800X0200Y0200     S3      
327m0152            R394  -1          A01X+007875Y+017500X0280Y0240R180 S1      
317m0153            TP34  -1   MD0100PA00X+006450Y+012950X0200Y0200     S2      
327m0153            R365  -2          A01X+005800Y+014440X0280Y0240R270 S1      
327m0153            U13   -1   M      A01X+005768Y+013500X0380Y0120R270 S1      
327m0153            U24   -J15        A01X+042066Y+018828X0197Y0197R090 S1      
317m0153            VIA   -    MD0080PA00X+041869Y+019025X0180Y0180     S0      
317m0153            VIA   -    MD0100PA00X+009550Y+019200X0200Y0200     S3      
327m0154            U13   -7          A01X+005571Y+012169X0380Y0120R270 S1      
327m0154            R377  -2   M      A01X+005050Y+011259X0280Y0240R090 S1      
317m0154            TP30  -1   MD0100PA00X+005650Y+011300X0200Y0200     S2      
327m0154            U24   -H15        A01X+041672Y+018828X0197Y0197R090 S1      
317m0154            VIA   -    MD0080PA00X+041475Y+019025X0180Y0180     S0      
317m0154            VIA   -    MD0100PA00X+008850Y+014900X0200Y0200     S3      
317m0154            VIA   -    MD0100PA00X+009900Y+017550X0200Y0200     S3      
327SMA3_LED_RED_N   U33   -16         A01X+040489Y+040314X0490Y0120R180 S1      
317SMA3_LED_RED_N   VIA   -    MD0080PA00X+039350Y+040000X0180Y0180R090 S3      
317SMA3_LED_RED_N   VIA   -    MD0100PA00X+003320Y+026251X0200Y0200     S3      
327SMA3_LED_RED_N   R393  -1          A01X+003320Y+026641X0280Y0240R090 S1      
327m0155            U33   -15         A01X+040474Y+040511X0460Y0120R180 S1      
317m0155            VIA   -    MD0080PA00X+038850Y+040000X0180Y0180R090 S3      
317m0155            VIA   -    MD0100PA00X+004050Y+026200X0200Y0200     S3      
327m0155            R392  -1          A01X+003770Y+026641X0280Y0240R090 S1      
327m0156            U33   -17         A01X+040489Y+040117X0490Y0120R180 S1      
317m0156            VIA   -    MD0080PA00X+039850Y+040000X0180Y0180     S3      
317m0156            VIA   -    MD0100PA00X+001900Y+026250X0200Y0200     S3      
327m0156            R391  -1          A01X+001970Y+026641X0280Y0240R090 S1      
317m0157            TP33  -1   MD0100PA00X+006200Y+019950X0200Y0200     S2      
327m0157            U16   -1          A01X+005768Y+019209X0380Y0120R270 S1      
327m0157            R331  -2          A01X+005750Y+020490X0280Y0240R270 S1      
327m0157            U24   -M13        A01X+043247Y+018041X0197Y0197R090 S1      
317m0157            VIA   -    MD0080PA00X+043444Y+018237X0180Y0180     S0      
317m0157            VIA   -    MD0100PA00X+007500Y+014170X0200Y0200     S3      
327m0158            U24   -L13        A01X+042853Y+018041X0197Y0197R090 S1      
317m0158            VIA   -    MD0080PA00X+042656Y+018237X0180Y0180     S0      
317m0158            VIA   -    MD0100PA00X+009520Y+015100X0200Y0200     S3      
317m0158            TP29  -1   MD0100PA00X+005450Y+017100X0200Y0200     S2      
327m0158            R383  -2          A01X+005560Y+016500X0280Y0240     S1      
327m0158            U16   -7          A01X+005571Y+017878X0380Y0120R270 S1      
327SMA2_LED_RED_N   U33   -13         A01X+041046Y+040871X0120Y0490R180 S1      
317SMA2_LED_RED_N   VIA   -    MD0100PA00X+004150Y+012750X0200Y0200     S3      
327SMA2_LED_RED_N   R390  -1          A01X+008210Y+012000X0280Y0240R180 S1      
317SMA2_LED_RED_N   VIA   -    MD0100PA00X+008700Y+012000X0200Y0200     S3      
317SMA2_LED_RED_N   VIA   -    MD0080PA00X+007558Y+041900X0180Y0180R180 S3      
317SMA2_LED_RED_N   VIA   -    MD0080PA00X+039800Y+041850X0180Y0180     S3      
327m0159            U33   -12         A01X+041243Y+040871X0120Y0490R180 S1      
317m0159            VIA   -    MD0100PA00X+004650Y+013300X0200Y0200     S3      
327m0159            R389  -1          A01X+008210Y+013000X0280Y0240R180 S1      
317m0159            VIA   -    MD0100PA00X+008700Y+013000X0200Y0200     S3      
317m0159            VIA   -    MD0080PA00X+007050Y+041900X0180Y0180R180 S3      
317m0159            VIA   -    MD0080PA00X+040300Y+041850X0180Y0180     S3      
327m0160            U33   -14         A01X+040849Y+040886X0120Y0460R180 S1      
317m0160            VIA   -    MD0100PA00X+004141Y+013259X0200Y0200     S3      
327m0160            R388  -1          A01X+008210Y+010500X0280Y0240R180 S1      
317m0160            VIA   -    MD0100PA00X+008900Y+011050X0200Y0200     S3      
317m0160            VIA   -    MD0100PA00X+008050Y+042050X0200Y0200     S3      
317m0160            VIA   -    MD0080PA00X+039300Y+041850X0180Y0180     S3      
317m0161            TP32  -1   MD0100PA00X+006470Y+025170X0200Y0200     S2      
327m0161            U24   -K13        A01X+042460Y+018041X0197Y0197R090 S1      
317m0161            VIA   -    MD0080PA00X+042263Y+018237X0180Y0180     S0      
317m0161            VIA   -    MD0100PA00X+009390Y+015520X0200Y0200     S3      
327m0161            U15   -1          A01X+005768Y+024917X0380Y0120R270 S1      
327m0161            R361  -2   M      A01X+005780Y+025690X0280Y0240R270 S1      
317m0162            TP28  -1   MD0100PA00X+005750Y+022650X0200Y0200     S2      
327m0162            R381  -2          A01X+005145Y+022750X0280Y0240R090 S1      
327m0162            U15   -7          A01X+005571Y+023587X0380Y0120R270 S1      
327m0162            U24   -K14        A01X+042460Y+018434X0197Y0197R090 S1      
317m0162            VIA   -    MD0080PA00X+042263Y+018631X0180Y0180     S0      
317m0162            VIA   -    MD0100PA00X+009570Y+022750X0200Y0200     S3      
327SMA1_LED_RED_N   U33   -9          A01X+041834Y+040871X0120Y0490R180 S1      
317SMA1_LED_RED_N   VIA   -    MD0080PA00X+041680Y+042400X0180Y0180     S3      
317SMA1_LED_RED_N   VIA   -    MD0080PA00X+008550Y+042050X0180Y0180R180 S3      
317SMA1_LED_RED_N   VIA   -    MD0100PA00X+001500Y+027900X0200Y0200     S3      
317SMA1_LED_RED_N   VIA   -    MD0100PA00X+003260Y+014870X0200Y0200     S3      
327SMA1_LED_RED_N   R387  -1          A01X+003260Y+015270X0280Y0240R090 S1      
327m0163            U33   -8          A01X+042031Y+040886X0120Y0460R180 S1      
317m0163            VIA   -    MD0100PA00X+000900Y+028600X0200Y0200     S3      
317m0163            VIA   -    MD0080PA00X+009000Y+042050X0180Y0180R180 S3      
317m0163            VIA   -    MD0080PA00X+042234Y+042400X0180Y0180     S3      
327m0163            R386  -1          A01X+004160Y+015270X0280Y0240R090 S1      
317m0163            VIA   -    MD0100PA00X+004160Y+014880X0200Y0200     S3      
327m0164            U33   -10         A01X+041637Y+040871X0120Y0490R180 S1      
317m0164            VIA   -    MD0100PA00X+000900Y+027900X0200Y0200     S3      
317m0164            VIA   -    MD0080PA00X+009800Y+042000X0180Y0180R180 S3      
317m0164            VIA   -    MD0080PA00X+041400Y+041900X0180Y0180     S3      
327m0164            R385  -1          A01X+001910Y+015270X0280Y0240R090 S1      
317m0164            VIA   -    MD0100PA00X+001910Y+014880X0200Y0200     S3      
327m0165            U33   -23         A01X+041046Y+038969X0120Y0490R180 S1      
317m0165            VIA   -    MD0080PA00X+041046Y+038300X0180Y0180R090 S3      
317m0165            VIA   -    MD0100PA00X+003300Y+031450X0200Y0200     S3      
327m0165            R399  -1          A01X+003300Y+031890X0280Y0240R090 S1      
327m0166            U33   -22         A01X+040849Y+038954X0120Y0460R180 S1      
317m0166            VIA   -    MD0080PA00X+040546Y+038300X0180Y0180R090 S3      
317m0166            VIA   -    MD0100PA00X+004300Y+031450X0200Y0200     S3      
327m0166            R398  -1          A01X+004300Y+031890X0280Y0240R090 S1      
327m0167            U33   -24         A01X+041243Y+038969X0120Y0490R180 S1      
317m0167            VIA   -    MD0080PA00X+041546Y+038300X0180Y0180     S3      
317m0167            VIA   -    MD0100PA00X+001800Y+031450X0200Y0200     S3      
327m0167            R397  -1          A01X+001800Y+031890X0280Y0240R090 S1      
327m0168            L18   -2          A01X+008985Y+026320X0300Y0340R180 S1      
327m0168            R350  -2          A01X+007695Y+025250X0280Y0240R270 S1      
327m0168            R347  -2          A01X+006425Y+026140X0280Y0240R180 S1      
327m0168            R71   -1          A01X+008065Y+027890X0280Y0240R090 S1      
327m0168            U28   -10         A01X+008200Y+026807X0140Y0110R180 S1      
327m0168            C277  -1          A01X+009090Y+027280X0280Y0240     S1      
327m0168            C278  -1          A01X+009085Y+026830X0280Y0240     S1      
317m0168            VIA   -    MD0100PA00X+008690Y+026720X0200Y0200R270 S3      
317m0168            VIA   -    MD0080PA00X+008710Y+027130X0180Y0180R180 S3      
317m0168            VIA   -    MD0080PA00X+006860Y+027400X0180Y0180R270 S3      
327m0168            R70   -1          A01X+006845Y+027090X0280Y0240R180 S1      
317m0168            VIA   -    MD0100PA00X+006425Y+025800X0200Y0200     S3      
317m0168            VIA   -    MD0080PA00X+007360Y+025250X0180Y0180R270 S3      
317m0168            VIA   -    MD0100PA00X+007140Y+023290X0200Y0200     S3      
327m0168            U32   -1          A01X+007826Y+022465X0180Y0600R180 S1      
327m0168            C313  -1   M      A01X+007140Y+022940X0280Y0240R270 S1      
317VDD_BNO085       VIA   -     D0080PA00X+034290Y+024680X0180Y0180     S3      
327VDD_BNO085       C281  -1          A01X+034350Y+025110X0280Y0240R090 S1      
327VDD_BNO085       L19   -1   M      A01X+034910Y+025090X0300Y0340R090 S1      
327VDD_BNO085       C280  -1          A01X+033848Y+025110X0280Y0240R090 S1      
327VDD_BNO085       U29   -28         A01X+034515Y+023829X0270Y0100     S1      
327VDD_BNO085       U29   -3          A01X+033998Y+024050X0100Y0230     S1      
327m0169            R168  -2          A10X+034700Y+023340X0280Y0240R090 S2      
317m0169            VIA   -    MD0100PA00X+035100Y+023324X0200Y0200     S3      
327m0169            U29   -26         A01X+034515Y+023435X0270Y0100     S1      
327m0169            Y1    -1   M      A01X+035700Y+023324X0330Y0550R090 S1      
327m0169            C47   -1          A01X+036367Y+023464X0120Y0150R270 S1      
317m0170            VIA   -    MD0080PA00X+032780Y+024680X0180Y0180     S3      
327m0170            R303  -1          A01X+032850Y+025110X0280Y0240R090 S1      
327m0170            U29   -5          A01X+033605Y+024050X0100Y0230     S1      
317m0171            VIA   -    MD0080PA00X+032430Y+025470X0180Y0180     S3      
327m0171            R305  -1          A01X+032010Y+025690X0280Y0240R180 S1      
327m0171            U29   -6          A01X+033285Y+024026X0270Y0100     S1      
317m0172            TP61  -1    D0100PA00X+033850Y+021350X0200Y0200R180 S2      
327m0172            U29   -18         A01X+033998Y+022230X0100Y0230     S1      
317m0173            VIA   -    MD0080PA00X+032400Y+023600X0180Y0180     S3      
327m0173            U29   -10         A01X+033285Y+023238X0270Y0100     S1      
327m0173            R307  -1          A01X+032010Y+024790X0280Y0240R180 S1      
327m0173            R306  -2   M      A01X+032010Y+024340X0280Y0240     S1      
317m0174            VIA   -    MD0080PA00X+032850Y+023864X0180Y0180     S3      
327m0174            C285  -1          A01X+032010Y+025240X0280Y0240R180 S1      
327m0174            U29   -9          A01X+033285Y+023435X0270Y0100     S1      
327m0175            R351  -1          A01X+008350Y+025660X0280Y0240R270 S1      
317m0175            VIA   -    MD0100PA00X+008320Y+026030X0200Y0200     S3      
327m0175            U28   -7          A01X+007993Y+026305X0110Y0140R180 S1      
327m0176            R350  -1          A01X+007695Y+025670X0280Y0240R270 S1      
317m0176            VIA   -    MD0080PA00X+007796Y+026010X0180Y0180     S3      
327m0176            U28   -6          A01X+007796Y+026305X0110Y0140R180 S1      
327m0177            R347  -1   M      A01X+006845Y+026140X0280Y0240R180 S1      
317m0177            VIA   -     D0100PA00X+006950Y+025780X0200Y0200     S3      
327m0177            U28   -5          A01X+007590Y+026413X0140Y0110R180 S1      
327m0178            R346  -1          A01X+006610Y+027900X0280Y0240R180 S1      
317m0178            VIA   -    MD0080PA00X+007200Y+027140X0180Y0180     S3      
327m0178            U28   -3          A01X+007590Y+026807X0140Y0110R180 S1      
327m0179            R343  -1          A10X+008580Y+027890X0280Y0240R270 S2      
317m0179            VIA   -    MD0080PA00X+008250Y+027320X0180Y0180     S3      
327m0179            U28   -1          A01X+007993Y+026915X0110Y0140R180 S1      
327VDD3V3_SHT31A    U27   -5          A01X+060195Y+021438X0410Y0120R090 S1      
327VDD3V3_SHT31A    L17   -2          A01X+060330Y+023240X0300Y0340R180 S1      
317VDD3V3_SHT31A    VIA   -    MD0100PA00X+060195Y+021885X0200Y0200     S3      
327VDD3V3_SHT31A    C275  -1   M      A01X+060290Y+022700X0280Y0240     S1      
327VDD3V3_SHT31A    C274  -1   M      A01X+060290Y+022250X0280Y0240     S1      
327m0180            U22   -6          A01X+044198Y+029252X0330Y0120R180 S1      
327m0180            R295  -2          A10X+043660Y+029750X0280Y0240R180 S2      
327m0180            R143  -2          A01X+045240Y+029950X0280Y0240R180 S1      
317m0180            VIA   -    MD0080PA00X+044150Y+029750X0180Y0180     S3      
327m0181            R280  -1          A10X+061400Y+042610X0280Y0240R090 S2      
317m0181            VIA   -    MD0100PA00X+060942Y+042756X0200Y0200     S3      
327m0181            DS11  -A          A01X+061437Y+042756X0310Y0310R270 S1      
327m0182            VIA   -           A10X+026450Y+021400X0300Y0300     S2      
327m0182            U12   -3   M      A10X+026526Y+021935X0200Y0470R180 S2      
327m0182            R267  -1          A10X+026410Y+023750X0280Y0240     S2      
317m0183            VIA   -    MD0100PA00X+009590Y+027890X0200Y0200     S3      
317m0183            VIA   -    MD0100PA00X+008450Y+021800X0200Y0200     S3      
327m0183            J18   -2          A01X+008040Y+021510X0390Y0410R180 S1      
327m0183            R91   -2          A10X+009080Y+027890X0280Y0240R090 S2      
327R_SHT3X_RST_N    U27   -6          A01X+059998Y+021438X0410Y0120R090 S1      
317R_SHT3X_RST_N    TP26  -1    D0100PA00X+059550Y+023900X0200Y0200     S2      
317R_SHT3X_RST_N    VIA   -    MD0080PA00X+059415Y+022050X0180Y0180R180 S3      
327R_SHT3X_RST_N    R298  -1   M      A01X+059415Y+023300X0280Y0240R180 S1      
327R_SHT3X_RST_N    R297  -1   M      A01X+059415Y+022840X0280Y0240R180 S1      
327R_SHT3X_RST_N    R296  -2   M      A01X+059415Y+022390X0280Y0240     S1      
327m0184            U27   -3          A01X+059998Y+020442X0410Y0120R090 S1      
317m0184            VIA   -    MD0080PA00X+060190Y+020010X0180Y0180R180 S3      
327m0184            R299  -1          A01X+060190Y+019506X0280Y0240R270 S1      
317m0184            TP27  -1    D0100PA00X+058700Y+018400X0200Y0200     S2      
317m0185            VIA   -    MD0080PA00X+034593Y+021700X0180Y0180     S3      
327m0185            U29   -20         A01X+034515Y+022254X0270Y0100     S1      
327m0185            R76   -2          A10X+034190Y+022100X0280Y0240     S2      
317m0186            VIA   -    MD0100PA00X+034400Y+021200X0200Y0200     S3      
327m0186            U29   -19         A01X+034195Y+022230X0100Y0230     S1      
327m0186            R77   -2          A10X+033710Y+022100X0280Y0240R180 S2      
317m0187            VIA   -    MD0080PA00X+043444Y+019418X0180Y0180     S0      
317m0187            VIA   -    MD0080PA00X+031800Y+026850X0180Y0180     S3      
327m0187            U24   -M16        A01X+043247Y+019222X0197Y0197R090 S1      
317m0187            VIA   -    MD0080PA00X+035230Y+017500X0180Y0180R090 S3      
327m0187            R266  -1          A01X+035540Y+017455X0280Y0240R090 S1      
317IO_L24P_35       TP203 -1    D0100PA00X+047120Y+011570X0200Y0200R090 S2      
317IO_L24P_35       VIA   -    MD0080PA00X+044231Y+015088X0180Y0180     S0      
327IO_L24P_35       U24   -P6         A01X+044034Y+015285X0197Y0197R090 S1      
317IO_L24P_34       TP140 -1    D0100PA00X+046200Y+016269X0200Y0200     S2      
327IO_L24P_34       U24   -W9         A01X+046003Y+016466X0197Y0197R090 S1      
317IO_L24N_35       TP204 -1    D0100PA00X+042900Y+012350X0200Y0200R090 S2      
317IO_L24N_35       VIA   -    MD0080PA00X+043837Y+014694X0180Y0180     S0      
327IO_L24N_35       U24   -N5         A01X+043641Y+014891X0197Y0197R090 S1      
317IO_L23P_35       TP195 -1    D0100PA00X+041500Y+012350X0200Y0200R090 S2      
317IO_L23P_35       VIA   -    MD0080PA00X+043444Y+015088X0180Y0180     S0      
327IO_L23P_35       U24   -M6         A01X+043247Y+015285X0197Y0197R090 S1      
317IO_L23P_34       TP138 -1    D0100PA00X+050350Y+014900X0200Y0200     S2      
317IO_L23P_34       VIA   -    MD0080PA00X+046593Y+015875X0180Y0180     S0      
327IO_L23P_34       U24   -Y8         A01X+046396Y+016072X0197Y0197R090 S1      
317IO_L23N_35       TP196 -1    D0100PA00X+041850Y+011700X0200Y0200R090 S2      
317IO_L23N_35       VIA   -    MD0080PA00X+043444Y+014694X0180Y0180     S0      
327IO_L23N_35       U24   -M5         A01X+043247Y+014891X0197Y0197R090 S1      
317IO_L22P_35       TP201 -1    D0100PA00X+048160Y+012580X0200Y0200R090 S2      
327IO_L22P_35       U24   -P2         A01X+044034Y+013710X0197Y0197R090 S1      
317IO_L22N_35       TP202 -1    D0100PA00X+046650Y+011040X0200Y0200R090 S2      
317IO_L22N_35       VIA   -    MD0080PA00X+043837Y+013513X0180Y0180     S0      
327IO_L22N_35       U24   -N2         A01X+043641Y+013710X0197Y0197R090 S1      
317IO_L22N_34       TP137 -1    D0100PA00X+049100Y+015400X0200Y0200     S2      
327IO_L22N_34       U24   -AB8        A01X+047184Y+016072X0197Y0197R090 S1      
317IO_L21P_35       TP193 -1    D0100PA00X+047680Y+012070X0200Y0200R090 S2      
317IO_L21P_35       VIA   -    MD0080PA00X+044231Y+014694X0180Y0180     S0      
327IO_L21P_35       U24   -P5         A01X+044034Y+014891X0197Y0197R090 S1      
317IO_L21P_34       TP134 -1    D0100PA00X+050300Y+015500X0200Y0200R270 S2      
317IO_L21P_34       VIA   -    MD0080PA00X+045806Y+016269X0180Y0180     S0      
327IO_L21P_34       U24   -V9         A01X+045609Y+016466X0197Y0197R090 S1      
317IO_L21N_35       TP194 -1    D0100PA00X+048280Y+011030X0200Y0200R090 S2      
317IO_L21N_35       VIA   -    MD0080PA00X+044231Y+014300X0180Y0180     S0      
327IO_L21N_35       U24   -P4         A01X+044034Y+014497X0197Y0197R090 S1      
317IO_L20P_35       TP199 -1    D0100PA00X+048300Y+013300X0200Y0200R090 S2      
327IO_L20P_35       U24   -R1         A01X+044428Y+013316X0197Y0197R090 S1      
317IO_L20N_35       TP200 -1    D0100PA00X+042200Y+012350X0200Y0200R090 S2      
327IO_L20N_35       U24   -P1         A01X+044034Y+013316X0197Y0197R090 S1      
317FPGA_USR_LED1    VIA   -    MD0080PA00X+038313Y+017837X0180Y0180     S3      
317FPGA_USR_LED1    VIA   -    MD0100PA00X+060256Y+041750X0200Y0200     S3      
327FPGA_USR_LED1    DS10  -C          A01X+060256Y+042165X0310Y0310R270 S1      
327FPGA_USR_LED1    U24   -A13        A01X+038916Y+018041X0197Y0197R090 S1      
317FPGA_USR_LED0    VIA   -    MD0100PA00X+061437Y+041750X0200Y0200     S3      
327FPGA_USR_LED0    DS11  -C          A01X+061437Y+042165X0310Y0310R270 S1      
317FPGA_USR_LED0    VIA   -    MD0080PA00X+038719Y+018631X0180Y0180     S0      
327FPGA_USR_LED0    U24   -A14        A01X+038916Y+018434X0197Y0197R090 S1      
317m0188            VIA   -    MD0080PA00X+041475Y+020600X0180Y0180     S0      
327m0188            U24   -H19        A01X+041672Y+020403X0197Y0197R090 S1      
317m0188            VIA   -    MD0100PA00X+058300Y+029700X0200Y0200     S3      
317m0188            VIA   -    MD0080PA00X+058995Y+023660X0180Y0180R180 S3      
327m0188            R298  -2          A01X+058995Y+023300X0280Y0240R180 S1      
327m0189            R60   -1          A10X+032560Y+034750X0280Y0240R180 S2      
317m0189            VIA   -    MD0080PA00X+036112Y+034988X0180Y0180R090 S3      
317m0189            VIA   -    MD0080PA00X+045412Y+019418X0180Y0180     S0      
327m0189            U24   -U16        A01X+045215Y+019222X0197Y0197R090 S1      
317m0190            VIA   -    MD0080PA00X+042263Y+019418X0180Y0180     S0      
327m0190            U24   -K16        A01X+042460Y+019222X0197Y0197R090 S1      
317m0190            VIA   -    MD0080PA00X+019650Y+007650X0180Y0180     S3      
327m0190            R354  -1          A01X+019977Y+006320X0280Y0240R270 S1      
317m0191            VIA   -    MD0080PA00X+041869Y+019812X0180Y0180     S0      
317m0191            VIA   -    MD0100PA00X+031200Y+025650X0200Y0200     S3      
317m0191            VIA   -    MD0100PA00X+031190Y+022990X0200Y0200     S3      
327m0191            R78   -2          A01X+031590Y+022990X0280Y0240R180 S1      
327m0191            U24   -J17        A01X+042066Y+019615X0197Y0197R090 S1      
317m0192            VIA   -    MD0080PA00X+042656Y+019025X0180Y0180     S0      
327m0192            R80   -1          A10X+033350Y+025530X0280Y0240R090 S2      
317m0192            VIA   -    MD0100PA00X+033850Y+025900X0200Y0200     S3      
327m0192            U24   -L15        A01X+042853Y+018828X0197Y0197R090 S1      
317m0193            VIA   -    MD0100PA00X+051550Y+020100X0200Y0200     S3      
317m0193            VIA   -    MD0100PA00X+060250Y+018300X0200Y0200     S3      
327m0193            R299  -2          A01X+060190Y+019086X0280Y0240R270 S1      
327m0193            R300  -2          A10X+060190Y+019086X0280Y0240R090 S2      
317m0193            VIA   -    MD0080PA00X+041869Y+020600X0180Y0180     S0      
327m0193            U24   -J19        A01X+042066Y+020403X0197Y0197R090 S1      
317m0194            VIA   -    MD0080PA00X+043444Y+019025X0180Y0180     S0      
327m0194            R267  -2          A10X+025990Y+023750X0280Y0240     S2      
327m0194            R107  -2   M      A10X+025510Y+023750X0280Y0240R180 S2      
327m0194            U24   -M15        A01X+043247Y+018828X0197Y0197R090 S1      
317m0194            VIA   -    MD0100PA00X+025540Y+029010X0200Y0200     S3      
317m0195            VIA   -    MD0080PA00X+047500Y+016300X0180Y0180     S2      
327m0195            R288  -2          A01X+048840Y+016750X0280Y0240R180 S1      
327m0195            R93   -2   M      A01X+048840Y+016300X0280Y0240R180 S1      
327m0195            U24   -AA9        A01X+046790Y+016466X0197Y0197R090 S1      
317m0196            VIA   -    MD0100PA00X+032050Y+017000X0200Y0200     S3      
327m0196            R96   -2   M      A01X+031660Y+016950X0280Y0240     S1      
327m0196            R287  -1          A01X+031660Y+016450X0280Y0240R180 S1      
327m0196            U24   -AB10       A01X+047184Y+016860X0197Y0197R090 S1      
317m0196            VIA   -    MD0100PA00X+047750Y+017050X0200Y0200     S3      
327m0197            R92   -2          A10X+048840Y+018550X0280Y0240     S2      
317m0197            VIA   -    MD0100PA00X+048400Y+018550X0200Y0200     S3      
317m0197            VIA   -    MD0080PA00X+045806Y+018237X0180Y0180     S0      
327m0197            U24   -V13        A01X+045609Y+018041X0197Y0197R090 S1      
327m0197            R502  -2          A10X+045609Y+018434X0250Y0250     S2      
327m0198            R271  -2   M      A10X+046790Y+018828X0250Y0250R270 S2      
327m0198            R111  -1          A10X+048850Y+035040X0280Y0240R270 S2      
317m0198            VIA   -    MD0080PA00X+046593Y+018631X0180Y0180     S0      
327m0198            U24   -Y14        A01X+046396Y+018434X0197Y0197R090 S1      
317m0198            VIA   -    MD0100PA00X+048150Y+019300X0200Y0200     S3      
317m0198            VIA   -    MD0100PA00X+048850Y+034600X0200Y0200     S3      
327m0199            R270  -2          A10X+046003Y+018828X0250Y0250R180 S2      
327m0199            R117  -2          A01X+048350Y+035040X0280Y0240R270 S1      
317m0199            VIA   -    MD0080PA00X+046200Y+018631X0180Y0180     S0      
317m0199            VIA   -    MD0100PA00X+048350Y+034600X0200Y0200     S3      
327m0199            U24   -W14        A01X+046003Y+018434X0197Y0197R090 S1      
317m0200            VIA   -    MD0100PA00X+031250Y+022540X0200Y0200     S3      
327m0200            R289  -2          A01X+031590Y+022090X0280Y0240R180 S1      
327m0200            R79   -1   M      A01X+031590Y+022540X0280Y0240     S1      
327m0200            U24   -L14        A01X+042853Y+018434X0197Y0197R090 S1      
317m0200            VIA   -    MD0080PA00X+042656Y+018631X0180Y0180     S2      
317m0200            VIA   -    MD0100PA00X+031200Y+026900X0200Y0200     S3      
317m0201            VIA   -    MD0100PA00X+045650Y+030550X0200Y0200     S3      
317m0201            VIA   -    MD0100PA00X+043000Y+038100X0200Y0200     S3      
317m0201            VIA   -    MD0080PA00X+013825Y+037225X0180Y0180R180 S3      
327m0201            R294  -2          A01X+014250Y+038510X0280Y0240R180 S1      
317m0201            VIA   -    MD0080PA00X+059050Y+030150X0180Y0180     S3      
327m0201            J10   -10         A01X+060184Y+030150X0500Y1400R090 S1      
317m0201            TP46  -1   MD0100PA00X+054100Y+009600X0200Y0200     S2      
327m0201            R230  -2          A10X+054040Y+006400X0280Y0240     S2      
327m0201            R209  -1          A10X+048840Y+017650X0280Y0240R180 S2      
317m0201            VIA   -    MD0100PA00X+048503Y+017493X0200Y0200     S3      
327m0201            U24   -U12        A01X+045215Y+017647X0197Y0197R090 S1      
317m0201            VIA   -    MD0080PA00X+045412Y+017844X0180Y0180     S0      
327m0201            R143  -1   M      A01X+045660Y+029950X0280Y0240R180 S1      
317m0201            VIA   -    MD0100PA00X+052600Y+029550X0200Y0200     S3      
317m0202            VIA   -    MD0080PA00X+036250Y+009200X0180Y0180     S3      
327m0202            U11   -5          A01X+035821Y+019234X0080Y0370R090 S1      
317m0202            VIA   -    MD0080PA00X+061996Y+022767X0180Y0180R180 S3      
327m0202            U9    -6   M      A01X+063073Y+022018X0200Y0470     S1      
327m0202            J11   -3          A01X+064105Y+021102X0160Y0530R090 S1      
327m0203            U9    -4   M      A01X+062325Y+022018X0200Y0470     S1      
327m0203            J11   -2          A01X+064105Y+020846X0160Y0530R090 S1      
327m0203            U11   -6          A01X+035821Y+019391X0080Y0370R090 S1      
317m0203            VIA   -    MD0080PA00X+036570Y+009200X0180Y0180     S3      
317m0203            VIA   -    MD0080PA00X+061996Y+022447X0180Y0180R180 S3      
317BNO080_SA0       VIA   -    MD0100PA00X+033255Y+021355X0200Y0200     S3      
327BNO080_SA0       R302  -1          A01X+032010Y+021640X0280Y0240R180 S1      
327BNO080_SA0       R290  -2   M      A01X+032960Y+021650X0280Y0240     S1      
327BNO080_SA0       U29   -17         A01X+033802Y+022230X0100Y0230     S1      
327m0204            U29   -16         A01X+033605Y+022230X0100Y0230     S1      
317m0204            VIA   -    MD0100PA00X+033515Y+021788X0200Y0200     S3      
317m0204            VIA   -    MD0080PA00X+034400Y+029500X0180Y0180     S3      
327m0204            R330  -1          A10X+034400Y+029060X0280Y0240R090 S2      
327m0205            R363  -1          A10X+033500Y+028640X0280Y0240R270 S2      
327m0205            U29   -15         A01X+033285Y+022254X0270Y0100     S1      
317m0205            VIA   -    MD0100PA00X+032792Y+022158X0200Y0200     S3      
317m0205            VIA   -    MD0080PA00X+033435Y+028200X0180Y0180     S3      
327XP3R3V_FPGA_SR   U22   -5          A01X+044198Y+029055X0330Y0120R180 S1      
317XP3R3V_FPGA_SR   VIA   -    MD0100PA00X+044600Y+029400X0200Y0200     S3      
327XP3R3V_FPGA_SR   C236  -1          A01X+045240Y+029450X0280Y0240     S1      
327m0206            U22   -2          A01X+044198Y+028465X0330Y0120R180 S1      
327m0206            R237  -1          A01X+045240Y+028450X0280Y0240     S1      
317m0206            VIA   -    MD0100PA00X+044700Y+028300X0200Y0200     S3      
327m0206            R226  -2          A10X+045240Y+029450X0280Y0240     S2      
327m0206            R260  -2          A10X+045240Y+027950X0280Y0240     S2      
327m0206            C229  -1   M      A10X+045240Y+028450X0280Y0240R180 S2      
327m0206            C294  -1   M      A10X+045240Y+028950X0280Y0240R180 S2      
317XP3R3V_FPGA      VIA   -    MD0100PA00X+059950Y+011650X0200Y0200     S3      
327XP3R3V_FPGA      R20   -1          A01X+059560Y+011250X0280Y0240R180 S1      
317XP3R3V_FPGA      VIA   -    MD0100PA00X+031060Y+032600X0200Y0200R090 S3      
327XP3R3V_FPGA      R62   -2          A10X+030680Y+032600X0280Y0240R180 S2      
327XP3R3V_FPGA      R146  -1   M      A10X+032560Y+033850X0280Y0240R180 S2      
327XP3R3V_FPGA      R150  -1          A10X+032560Y+033400X0280Y0240R180 S2      
317XP3R3V_FPGA      VIA   -    MD0080PA00X+032220Y+033850X0180Y0180R180 S3      
327XP3R3V_FPGA      R151  -1          A10X+030680Y+033500X0280Y0240     S2      
317XP3R3V_FPGA      VIA   -    MD0080PA00X+031060Y+033500X0180Y0180R180 S3      
317XP3R3V_FPGA      VIA   -    MD0100PA00X+019590Y+033250X0200Y0200     S3      
327XP3R3V_FPGA      R422  -1          A01X+019590Y+032890X0280Y0240R270 S1      
327XP3R3V_FPGA      R149  -1          A10X+032560Y+032050X0280Y0240R180 S2      
317XP3R3V_FPGA      VIA   -    MD0080PA00X+032220Y+032050X0180Y0180R180 S3      
327XP3R3V_FPGA      R341  -1          A10X+034850Y+029060X0280Y0240R090 S2      
317XP3R3V_FPGA      VIA   -    MD0100PA00X+034900Y+029550X0200Y0200     S3      
327XP3R3V_FPGA      C123  -1          A10X+039800Y+034290X0280Y0240R270 S2      
317XP3R3V_FPGA      VIA   -    MD0100PA00X+039800Y+033650X0200Y0200     S3      
327XP3R3V_FPGA      U39   -5          A01X+039800Y+034056X0240Y0170R270 S1      
327XP3R3V_FPGA      R201  -2          A10X+037440Y+033700X0280Y0240     S2      
317XP3R3V_FPGA      VIA   -    MD0100PA00X+037000Y+033700X0200Y0200R270 S3      
327XP3R3V_FPGA      R199  -2          A10X+035060Y+033700X0280Y0240R180 S2      
317XP3R3V_FPGA      VIA   -    MD0100PA00X+035500Y+033700X0200Y0200     S3      
327XP3R3V_FPGA      C102  -1          A10X+041700Y+034290X0280Y0240R270 S2      
317XP3R3V_FPGA      VIA   -    MD0100PA00X+041750Y+033700X0200Y0200     S3      
327XP3R3V_FPGA      U40   -5          A01X+041750Y+034076X0240Y0170R270 S1      
327XP3R3V_FPGA      R457  -1          A10X+039730Y+032910X0280Y0240R180 S2      
327XP3R3V_FPGA      R200  -2   M      A10X+037440Y+032800X0280Y0240     S2      
327XP3R3V_FPGA      R191  -1          A10X+037440Y+032350X0280Y0240R180 S2      
317XP3R3V_FPGA      VIA   -    MD0100PA00X+037100Y+032600X0200Y0200R270 S3      
327XP3R3V_FPGA      R202  -2          A10X+035060Y+032800X0280Y0240R180 S2      
317XP3R3V_FPGA      VIA   -    MD0080PA00X+035500Y+032800X0180Y0180R180 S3      
317XP3R3V_FPGA      VIA   -    MD0100PA00X+034140Y+032350X0200Y0200     S3      
327XP3R3V_FPGA      U23   -8          A01X+034810Y+032350X0720Y0200R180 S1      
317XP3R3V_FPGA      VIA   -    MD0100PA00X+034100Y+030400X0200Y0200     S3      
327XP3R3V_FPGA      C199  -1   M      A01X+035820Y+028560X0280Y0240R090 S1      
327XP3R3V_FPGA      C198  -1          A01X+035820Y+028030X0280Y0240R270 S1      
317XP3R3V_FPGA      VIA   -    MD0080PA00X+035480Y+028560X0180Y0180R180 S3      
327XP3R3V_FPGA      R167  -1          A01X+036890Y+027100X0280Y0240     S1      
317XP3R3V_FPGA      VIA   -    MD0100PA00X+035768Y+027178X0200Y0200     S3      
327XP3R3V_FPGA      R342  -1          A10X+033950Y+028640X0280Y0240R270 S2      
317XP3R3V_FPGA      VIA   -    MD0100PA00X+033950Y+028200X0200Y0200     S3      
317XP3R3V_FPGA      TP58  -1   MD0100PA00X+035800Y+026150X0200Y0200     S2      
317XP3R3V_FPGA      VIA   -    MD0100PA00X+034850Y+026000X0200Y0200     S3      
317XP3R3V_FPGA      VIA   -    MD0100PA00X+035250Y+026000X0200Y0200     S3      
327XP3R3V_FPGA      C279  -1   M      A01X+035460Y+025550X0280Y0240R270 S1      
327XP3R3V_FPGA      L19   -2   M      A01X+034910Y+025630X0300Y0340R090 S1      
327XP3R3V_FPGA      R304  -1          A01X+033350Y+025530X0280Y0240R270 S1      
317XP3R3V_FPGA      VIA   -    MD0100PA00X+033350Y+025890X0200Y0200     S3      
317XP3R3V_FPGA      VIA   -    MD0100PA00X+032400Y+022075X0200Y0200     S3      
327XP3R3V_FPGA      R289  -1          A01X+032010Y+022090X0280Y0240R180 S1      
327XP3R3V_FPGA      R290  -1          A01X+032540Y+021650X0280Y0240     S1      
327XP3R3V_FPGA      R74   -1          A10X+034190Y+022550X0280Y0240R180 S2      
327XP3R3V_FPGA      R75   -1   M      A10X+033710Y+022550X0280Y0240     S2      
317XP3R3V_FPGA      VIA   -    MD0100PA00X+049050Y+021675X0200Y0200     S3      
327XP3R3V_FPGA      R193  -1          A01X+049260Y+021150X0280Y0240R180 S1      
327XP3R3V_FPGA      R264  -1          A10X+048840Y+020250X0280Y0240R180 S2      
317XP3R3V_FPGA      VIA   -    MD0100PA00X+048500Y+020274X0200Y0200     S3      
327XP3R3V_FPGA      R265  -1          A10X+049260Y+019750X0280Y0240     S2      
317XP3R3V_FPGA      VIA   -    MD0100PA00X+049650Y+019750X0200Y0200     S3      
317XP3R3V_FPGA      VIA   -    MD0100PA00X+034913Y+018663X0200Y0200R090 S3      
327XP3R3V_FPGA      U11   -12         A01X+035060Y+018919X0080Y0370R090 S1      
327XP3R3V_FPGA      C67   -1          A10X+035050Y+018310X0280Y0240R090 S2      
317XP3R3V_FPGA      VIA   -    MD0080PA00X+046593Y+016663X0180Y0180     S0      
327XP3R3V_FPGA      C210  -1          A10X+046396Y+016860X0250Y0250     S2      
327XP3R3V_FPGA      U24   -Y10        A01X+046396Y+016860X0197Y0197R090 S1      
327XP3R3V_FPGA      R164  -1          A01X+037600Y+023840X0280Y0240R090 S1      
317XP3R3V_FPGA      VIA   -    MD0100PA00X+037950Y+023750X0200Y0200     S3      
317XP3R3V_FPGA      VIA   -    MD0080PA00X+039900Y+020206X0180Y0180     S0      
327XP3R3V_FPGA      U24   -D18        A01X+040097Y+020009X0197Y0197R090 S1      
327XP3R3V_FPGA      C211  -1          A10X+039704Y+020009X0250Y0250     S2      
327XP3R3V_FPGA      C157  -1          A10X+039704Y+020403X0250Y0250     S2      
317XP3R3V_FPGA      VIA   -    MD0080PA00X+043444Y+018631X0180Y0180     S0      
327XP3R3V_FPGA      U24   -M14        A01X+043247Y+018434X0197Y0197R090 S1      
327XP3R3V_FPGA      C115  -1          A10X+043060Y+018370X0280Y0240R090 S2      
327XP3R3V_FPGA      C144  -1          A10X+043101Y+018978X0250Y0250R270 S2      
317XP3R3V_FPGA      VIA   -    MD0080PA00X+040294Y+019025X0180Y0180     S0      
327XP3R3V_FPGA      U24   -E15        A01X+040491Y+018828X0197Y0197R090 S1      
327XP3R3V_FPGA      C170  -1          A10X+040491Y+019222X0250Y0250R270 S2      
327XP3R3V_FPGA      C167  -1          A10X+040097Y+019222X0250Y0250     S2      
317XP3R3V_FPGA      VIA   -    MD0080PA00X+038550Y+019615X0180Y0180     S0      
327XP3R3V_FPGA      U24   -A17        A01X+038916Y+019615X0197Y0197R090 S1      
327XP3R3V_FPGA      C203  -1          A10X+039310Y+018434X0250Y0250R180 S2      
317XP3R3V_FPGA      VIA   -    MD0080PA00X+039113Y+018631X0180Y0180     S0      
327XP3R3V_FPGA      U24   -B14        A01X+039310Y+018434X0197Y0197R090 S1      
317XP3R3V_FPGA      VIA   -    MD0080PA00X+040688Y+017844X0180Y0180     S0      
327XP3R3V_FPGA      U24   -F12        A01X+040885Y+017647X0197Y0197R090 S1      
317XP3R3V_FPGA      VIA   -    MD0080PA00X+041869Y+018237X0180Y0180     S0      
327XP3R3V_FPGA      U24   -J13        A01X+042066Y+018041X0197Y0197R090 S1      
327XP3R3V_FPGA      C221  -1          A10X+042066Y+018434X0250Y0250R270 S2      
317XP3R3V_FPGA      VIA   -    MD0100PA00X+038600Y+025925X0200Y0200     S3      
327XP3R3V_FPGA      U22   -12         A01X+042922Y+028268X0330Y0120R180 S1      
327XP3R3V_FPGA      U22   -11         A01X+042922Y+028465X0330Y0120R180 S1      
327XP3R3V_FPGA      U22   -10         A01X+042922Y+028662X0330Y0120R180 S1      
327XP3R3V_FPGA      U22   -9          A01X+042922Y+028858X0330Y0120R180 S1      
327XP3R3V_FPGA      U22   -8          A01X+042922Y+029055X0330Y0120R180 S1      
327XP3R3V_FPGA      U22   -7          A01X+042922Y+029252X0330Y0120R180 S1      
327XP3R3V_FPGA      R435  -2          A01X+045750Y+024610X0280Y0240R090 S1      
327XP3R3V_FPGA      R502  -1          A10X+046003Y+018434X0250Y0250     S2      
327XP3R3V_FPGA      R295  -1          A10X+043240Y+029750X0280Y0240R180 S2      
327XP3R3V_FPGA      C126  -1          A10X+044822Y+019222X0250Y0250R270 S2      
317XP3R3V_FPGA      VIA   -    MD0100PA00X+037580Y+025520X0200Y0200R180 S3      
317XP3R3V_FPGA      VIA   -    MD0100PA00X+042090Y+025900X0200Y0200     S3      
327XP3R3V_FPGA      R325  -1   M      A01X+042090Y+025520X0280Y0240R270 S1      
327XP3R3V_FPGA      R327  -1   M      A01X+041500Y+025520X0280Y0240R270 S1      
327XP3R3V_FPGA      R308  -1   M      A01X+040930Y+025520X0280Y0240R270 S1      
327XP3R3V_FPGA      R292  -1   M      A01X+040370Y+025520X0280Y0240R270 S1      
327XP3R3V_FPGA      R170  -1   M      A01X+039780Y+025520X0280Y0240R270 S1      
327XP3R3V_FPGA      R172  -1   M      A01X+039190Y+025520X0280Y0240R270 S1      
327XP3R3V_FPGA      R285  -1   M      A01X+038010Y+025520X0280Y0240R270 S1      
327XP3R3V_FPGA      R283  -1   M      A01X+038600Y+025520X0280Y0240R270 S1      
317XP3R3V_FPGA      VIA   -    MD0080PA00X+046593Y+020993X0180Y0180     S0      
317XP3R3V_FPGA      VIA   -    MD0080PA00X+045412Y+020600X0180Y0180     S0      
317XP3R3V_FPGA      VIA   -    MD0080PA00X+045018Y+021781X0180Y0180     S0      
317XP3R3V_FPGA      VIA   -    MD0080PA00X+044625Y+019025X0180Y0180     S0      
317XP3R3V_FPGA      VIA   -    MD0080PA00X+044231Y+020206X0180Y0180     S0      
317XP3R3V_FPGA      VIA   -    MD0080PA00X+043837Y+021387X0180Y0180     S0      
317XP3R3V_FPGA      VIA   -    MD0080PA00X+042656Y+019812X0180Y0180     S0      
317XP3R3V_FPGA      VIA   -    MD0080PA00X+042263Y+020993X0180Y0180     S0      
317XP3R3V_FPGA      VIA   -    MD0080PA00X+041475Y+019418X0180Y0180     S0      
317XP3R3V_FPGA      VIA   -    MD0080PA00X+041082Y+020600X0180Y0180     S0      
317XP3R3V_FPGA      VIA   -    MD0080PA00X+040688Y+021781X0180Y0180     S0      
317XP3R3V_FPGA      VIA   -    MD0080PA00X+039507Y+021387X0180Y0180     S0      
317XP3R3V_FPGA      VIA   -    MD0080PA00X+046987Y+019812X0180Y0180     S0      
317XP3R3V_FPGA      VIA   -    MD0080PA00X+045806Y+019418X0180Y0180     S0      
317XP3R3V_FPGA      VIA   -    MD0080PA00X+047381Y+018631X0180Y0180     S0      
317XP3R3V_FPGA      VIA   -    MD0080PA00X+046200Y+018237X0180Y0180     S0      
317XP3R3V_FPGA      VIA   -    MD0080PA00X+045018Y+017844X0180Y0180     S0      
327XP3R3V_FPGA      C237  -1          A01X+041870Y+027920X0280Y0240R180 S1      
327XP3R3V_FPGA      C240  -1          A01X+042000Y+028550X0380Y0540R180 S1      
327XP3R3V_FPGA      C238  -1          A01X+042000Y+029360X0380Y0540R180 S1      
327XP3R3V_FPGA      C241  -1          A10X+042000Y+029360X0380Y0540     S2      
327XP3R3V_FPGA      C243  -1          A10X+042000Y+028550X0380Y0540     S2      
317XP3R3V_FPGA      VIA   -    MD0100PA00X+042490Y+029290X0200Y0200     S3      
317XP3R3V_FPGA      VIA   -    MD0100PA00X+042390Y+027850X0200Y0200     S3      
317XP3R3V_FPGA      VIA   -    MD0100PA00X+042490Y+028430X0200Y0200     S3      
327XP3R3V_FPGA      R223  -2   M      A10X+045750Y+024610X0280Y0240R270 S2      
327XP3R3V_FPGA      R215  -1          A10X+045300Y+024610X0280Y0240R090 S2      
317XP3R3V_FPGA      VIA   -    MD0100PA00X+045750Y+025000X0200Y0200     S3      
327XP3R3V_FPGA      R213  -1          A01X+043950Y+024610X0280Y0240R270 S1      
327XP3R3V_FPGA      R219  -1          A10X+043950Y+024610X0280Y0240R090 S2      
317XP3R3V_FPGA      VIA   -    MD0100PA00X+043950Y+025000X0200Y0200     S3      
317XP3R3V_FPGA      VIA   -    MD0100PA00X+047700Y+023900X0200Y0200     S3      
317XP3R3V_FPGA      VIA   -    MD0100PA00X+047100Y+023900X0200Y0200     S3      
327XP3R3V_FPGA      C174  -1          A01X+047400Y+024365X0450Y1040R090 S1      
327XP3R3V_FPGA      U24   -T12        A01X+044822Y+017647X0197Y0197R090 S1      
327XP3R3V_FPGA      C165  -1          A10X+045131Y+017550X0280Y0240R180 S2      
327XP3R3V_FPGA      C107  -1          A10X+045215Y+018041X0250Y0250R270 S2      
327XP3R3V_FPGA      U24   -W13        A01X+046003Y+018041X0197Y0197R090 S1      
327XP3R3V_FPGA      C202  -1          A10X+046396Y+018434X0250Y0250R270 S2      
327XP3R3V_FPGA      C139  -1          A10X+046396Y+018041X0250Y0250R180 S2      
327XP3R3V_FPGA      U24   -H16        A01X+041672Y+019222X0197Y0197R090 S1      
327XP3R3V_FPGA      C153  -1          A10X+041278Y+019615X0250Y0250     S2      
327XP3R3V_FPGA      C119  -1          A10X+041672Y+019615X0250Y0250R270 S2      
327XP3R3V_FPGA      U24   -L17        A01X+042853Y+019615X0197Y0197R090 S1      
327XP3R3V_FPGA      C149  -1          A10X+043000Y+019870X0280Y0240R270 S2      
327XP3R3V_FPGA      U24   -P18        A01X+044034Y+020009X0197Y0197R090 S1      
327XP3R3V_FPGA      U24   -R15        A01X+044428Y+018828X0197Y0197R090 S1      
327XP3R3V_FPGA      C132  -1          A10X+044428Y+019222X0250Y0250     S2      
327XP3R3V_FPGA      U24   -V16        A01X+045609Y+019222X0197Y0197R090 S1      
327XP3R3V_FPGA      C215  -1          A10X+046003Y+019222X0250Y0250R180 S2      
327XP3R3V_FPGA      C130  -1          A10X+046003Y+019615X0250Y0250R180 S2      
327XP3R3V_FPGA      U24   -AB14       A01X+047184Y+018434X0197Y0197R090 S1      
327XP3R3V_FPGA      C145  -1          A10X+047800Y+018631X0280Y0240R090 S2      
327XP3R3V_FPGA      U24   -AA17       A01X+046790Y+019615X0197Y0197R090 S1      
327XP3R3V_FPGA      C103  -1          A10X+047184Y+020009X0250Y0250R180 S2      
327XP3R3V_FPGA      U24   -C21        A01X+039704Y+021190X0197Y0197R090 S1      
327XP3R3V_FPGA      C216  -1          A10X+039310Y+021584X0250Y0250     S2      
327XP3R3V_FPGA      C140  -1          A10X+039310Y+021190X0250Y0250R090 S2      
327XP3R3V_FPGA      U24   -F22        A01X+040885Y+021584X0197Y0197R090 S1      
327XP3R3V_FPGA      C159  -1          A10X+040660Y+022150X0280Y0240     S2      
327XP3R3V_FPGA      U24   -G19        A01X+041278Y+020403X0197Y0197R090 S1      
327XP3R3V_FPGA      C112  -1          A10X+041278Y+020403X0250Y0250R180 S2      
327XP3R3V_FPGA      U24   -K20        A01X+042460Y+020796X0197Y0197R090 S1      
327XP3R3V_FPGA      C162  -1          A10X+042460Y+021190X0250Y0250R270 S2      
327XP3R3V_FPGA      U24   -N21        A01X+043641Y+021190X0197Y0197R090 S1      
327XP3R3V_FPGA      C223  -1          A10X+044034Y+021584X0250Y0250R270 S2      
327XP3R3V_FPGA      U24   -T22        A01X+044822Y+021584X0197Y0197R090 S1      
327XP3R3V_FPGA      C163  -1          A10X+044968Y+022200X0280Y0240     S2      
327XP3R3V_FPGA      U24   -U19        A01X+045215Y+020403X0197Y0197R090 S1      
327XP3R3V_FPGA      C134  -1          A10X+045215Y+020796X0250Y0250     S2      
327XP3R3V_FPGA      U24   -Y20        A01X+046396Y+020796X0197Y0197R090 S1      
327XP3R3V_FPGA      C154  -1          A10X+046790Y+021190X0250Y0250R270 S2      
327XP3R3V_FPGA      C172  -1          A10X+040875Y+023250X0450Y1040     S2      
317XP3R3V_FPGA      VIA   -    MD0100PA00X+040750Y+022500X0200Y0200     S3      
327XP3R3V_FPGA      U34   -5          A01X+036950Y+025135X0200Y0470     S1      
317XP3R3V_FPGA      VIA   -    MD0100PA00X+037350Y+024700X0200Y0200     S3      
327XP3R3V_FPGA      U34   -6          A01X+037324Y+025135X0200Y0470     S1      
327XP3R3V_FPGA      R194  -1   M      A01X+050010Y+013350X0280Y0240R180 S1      
327XP3R3V_FPGA      R221  -1          A01X+050010Y+013850X0280Y0240R180 S1      
317XP3R3V_FPGA      VIA   -    MD0100PA00X+050395Y+013350X0200Y0200     S3      
327XP3R3V_FPGA      R209  -2          A10X+049260Y+017650X0280Y0240R180 S2      
327XP3R3V_FPGA      R211  -1          A01X+049260Y+017650X0280Y0240R180 S1      
317XP3R3V_FPGA      VIA   -    MD0100PA00X+049700Y+017500X0200Y0200     S3      
327XP3R3V_FPGA      R217  -1          A10X+049260Y+016300X0280Y0240     S2      
317XP3R3V_FPGA      VIA   -    MD0100PA00X+049600Y+016300X0200Y0200     S3      
317XP3R3V_FPGA      VIA   -    MD0100PA00X+062200Y+012706X0200Y0200     S3      
317XP3R3V_FPGA      VIA   -    MD0100PA00X+038390Y+038460X0200Y0200     S3      
327XP3R3V_FPGA      R450  -2          A10X+038390Y+038100X0280Y0240     S2      
317XP3R3V_FPGA      VIA   -    MD0100PA00X+043840Y+038240X0200Y0200     S3      
327XP3R3V_FPGA      C89   -1   M      A01X+043840Y+037900X0280Y0240     S1      
327XP3R3V_FPGA      U30   -16         A01X+042745Y+037646X0140Y0620R090 S1      
327XP3R3V_FPGA      R269  -1          A10X+049890Y+034550X0280Y0240R180 S2      
317XP3R3V_FPGA      VIA   -    MD0100PA00X+049500Y+034600X0200Y0200     S3      
327XP3R3V_FPGA      R268  -1          A01X+049350Y+035040X0280Y0240R090 S1      
317XP3R3V_FPGA      VIA   -    MD0100PA00X+059400Y+018700X0200Y0200     S3      
317XP3R3V_FPGA      VIA   -    MD0100PA00X+063790Y+011690X0200Y0200     S3      
327XP3R3V_FPGA      U36   -8          A01X+062655Y+010834X0180Y0600R090 S1      
327XP3R3V_FPGA      C305  -2   M      A01X+063790Y+011350X0280Y0240R180 S1      
317XP3R3V_FPGA      VIA   -    MD0100PA00X+061050Y+019050X0200Y0200     S3      
327XP3R3V_FPGA      R300  -1          A10X+060190Y+019506X0280Y0240R090 S2      
327XP3R3V_FPGA      R65   -1   M      A10X+060690Y+019506X0280Y0240R090 S2      
317XP3R3V_FPGA      VIA   -    MD0100PA00X+059200Y+012706X0200Y0200     S3      
327XP3R3V_FPGA      J5    -12         A01X+059945Y+012706X0560Y0880R090 S1      
317XP3R3V_FPGA      VIA   -    MD0100PA00X+058800Y+009650X0200Y0200     S3      
327XP3R3V_FPGA      R410  -1          A01X+064210Y+009650X0280Y0240R180 S1      
327XP3R3V_FPGA      R414  -1   M      A01X+064210Y+010200X0280Y0240R180 S1      
317XP3R3V_FPGA      VIA   -    MD0100PA00X+064700Y+010800X0200Y0200     S3      
327XP3R3V_FPGA      R419  -1   M      A01X+064210Y+010800X0280Y0240R180 S1      
327XP3R3V_FPGA      L17   -1          A01X+060870Y+023240X0300Y0340R180 S1      
317XP3R3V_FPGA      VIA   -    MD0100PA00X+051900Y+030750X0200Y0200     S3      
317XP3R3V_FPGA      VIA   -    MD0100PA00X+053750Y+030400X0200Y0200     S3      
327XP3R3V_FPGA      R405  -1          A10X+054520Y+030610X0280Y0240R090 S2      
317XP3R3V_FPGA      VIA   -    MD0100PA00X+054100Y+028150X0200Y0200     S3      
327XP3R3V_FPGA      R403  -1          A10X+054520Y+028130X0280Y0240R090 S2      
317XP3R3V_FPGA      VIA   -    MD0100PA00X+055440Y+026750X0200Y0200     S3      
327XP3R3V_FPGA      R133  -1          A10X+055440Y+027210X0280Y0240     S2      
317XP3R3V_FPGA      VIA   -    MD0100PA00X+061865Y+024930X0200Y0200     S3      
327XP3R3V_FPGA      C40   -1          A01X+061410Y+023200X0280Y0240R270 S1      
317XP3R3V_FPGA      VIA   -    MD0100PA00X+061410Y+023640X0200Y0200     S3      
317XP3R3V_FPGA      VIA   -    MD0100PA00X+058500Y+022650X0200Y0200     S3      
327XP3R3V_FPGA      R296  -1          A01X+058995Y+022390X0280Y0240     S1      
317XP3R3V_FPGA      VIA   -    MD0100PA00X+056200Y+025487X0200Y0200     S3      
317XP3R3V_FPGA      VIA   -    MD0100PA00X+054200Y+029645X0200Y0200     S3      
327XP3R3V_FPGA      R404  -1          A10X+054520Y+029645X0280Y0240R090 S2      
327XP3R3V_FPGA      R64   -1          A10X+059190Y+019086X0280Y0240R270 S2      
327XP3R3V_FPGA      R68   -1          A01X+059690Y+019086X0280Y0240R090 S1      
317XP3R3V_FPGA      VIA   -    MD0100PA00X+046450Y+029850X0200Y0200     S3      
327XP3R3V_FPGA      U33   -3          A01X+042391Y+039723X0490Y0120R180 S1      
317XP3R3V_FPGA      VIA   -    MD0100PA00X+046100Y+030250X0200Y0200R090 S3      
317XP3R3V_FPGA      VIA   -    MD0080PA00X+044300Y+038650X0180Y0180R090 S3      
327XP3R3V_FPGA      R320  -1          A01X+043960Y+038650X0280Y0240R180 S1      
327XP3R3V_FPGA      R210  -2          A10X+052730Y+042010X0280Y0240R270 S2      
317XP3R3V_FPGA      VIA   -    MD0100PA00X+052210Y+041650X0200Y0200     S3      
327XP3R3V_FPGA      C315  -1          A10X+043540Y+039650X0280Y0240R180 S2      
327XP3R3V_FPGA      C314  -1          A01X+043540Y+039650X0280Y0240     S1      
317XP3R3V_FPGA      VIA   -    MD0080PA00X+043200Y+039650X0180Y0180R270 S3      
317XP3R3V_FPGA      VIA   -    MD0100PA00X+045350Y+038150X0200Y0200     S3      
327XP3R3V_FPGA      C81   -1          A01X+045300Y+038490X0280Y0240R090 S1      
327XP3R3V_FPGA      L16   -2          A01X+045980Y+038600X0300Y0340R180 S1      
327XP3R3V_FPGA      U38   -16         A01X+044085Y+032456X0140Y0620R090 S1      
327XP3R3V_FPGA      C97   -1   M      A01X+045090Y+032700X0280Y0240     S1      
317XP3R3V_FPGA      VIA   -    MD0100PA00X+045090Y+033090X0200Y0200     S3      
317XP3R3V_FPGA      VIA   -    MD0100PA00X+042350Y+041550X0200Y0200     S3      
327XP3R3V_FPGA      R317  -1          A10X+042240Y+040650X0280Y0240R180 S2      
327XP3R3V_FPGA      R318  -1   M      A10X+042240Y+041150X0280Y0240R180 S2      
317XP3R3V_FPGA      VIA   -    MD0100PA00X+045050Y+036850X0200Y0200     S3      
327XP3R3V_FPGA      R452  -2          A01X+044260Y+037000X0280Y0240     S1      
317XP3R3V_FPGA      VIA   -    MD0100PA00X+059750Y+042190X0200Y0200     S3      
327XP3R3V_FPGA      R280  -2          A10X+061400Y+042190X0280Y0240R090 S2      
327XP3R3V_FPGA      R279  -2   M      A10X+060270Y+042190X0280Y0240R090 S2      
317XP3R3V_FPGA      VIA   -    MD0100PA00X+058400Y+042190X0200Y0200     S3      
327XP3R3V_FPGA      R261  -2   M      A10X+057900Y+042190X0280Y0240R090 S2      
327XP3R3V_FPGA      R259  -2   M      A10X+056700Y+042190X0280Y0240R090 S2      
327XP3R3V_FPGA      R258  -2   M      A10X+055550Y+042190X0280Y0240R090 S2      
327XP3R3V_FPGA      R257  -2   M      A10X+054350Y+042190X0280Y0240R090 S2      
327XP3R3V_FPGA      R138  -2          A10X+054350Y+041660X0280Y0240R270 S2      
317XP3R3V_FPGA      VIA   -    MD0100PA00X+061450Y+039800X0200Y0200     S3      
327XP3R3V_FPGA      J5    -11         A01X+061465Y+012706X0560Y0920R090 S1      
327XP3R3V_FPGA      R474  -1          A01X+046940Y+008650X0280Y0240     S1      
327XP3R3V_FPGA      R475  -1          A01X+046940Y+007850X0280Y0240     S1      
317XP3R3V_FPGA      VIA   -    MD0100PA00X+046550Y+007850X0200Y0200     S3      
327XP3R3V_FPGA      R482  -1          A10X+046940Y+009650X0280Y0240R180 S2      
317XP3R3V_FPGA      VIA   -    MD0100PA00X+046350Y+009200X0200Y0200     S3      
327XP3R3V_FPGA      U37   -16         A01X+051245Y+009196X0140Y0620R090 S1      
327XP3R3V_FPGA      C92   -1   M      A01X+052490Y+009200X0280Y0240     S1      
317XP3R3V_FPGA      VIA   -    MD0100PA00X+052490Y+009900X0200Y0200     S3      
317XP3R3V_FPGA      VIA   -    MD0100PA00X+055300Y+010850X0200Y0200     S3      
327XP3R3V_FPGA      R477  -1          A01X+052910Y+008200X0280Y0240R180 S1      
317XP3R3V_FPGA      VIA   -    MD0100PA00X+053300Y+008200X0200Y0200     S3      
327XP3R3V_FPGA      R476  -1          A01X+052910Y+007600X0280Y0240R180 S1      
317XP3R3V_FPGA      VIA   -    MD0100PA00X+052650Y+006750X0200Y0200     S3      
317XP3R3V_FPGA      VIA   -    MD0100PA00X+029640Y+007020X0200Y0200     S3      
327XP3R3V_FPGA      U3    -5          A01X+028480Y+006306X0130Y0380R090 S1      
327XP3R3V_FPGA      R63   -1   M      A01X+029550Y+006210X0280Y0240     S1      
327XP3R3V_FPGA      C37   -1   M      A01X+029552Y+006678X0280Y0240     S1      
327XP3R3V_FPGA      R229  -1          A10X+055550Y+006080X0280Y0240R270 S2      
317XP3R3V_FPGA      VIA   -    MD0100PA00X+055150Y+005960X0200Y0200     S3      
317XP3R3V_FPGA      VIA   -    MD0100PA00X+020477Y+006778X0200Y0200     S3      
317XP3R3V_FPGA      VIA   -    MD0100PA00X+022850Y+007900X0200Y0200     S3      
317XP3R3V_FPGA      VIA   -    MD0100PA00X+022850Y+007550X0200Y0200     S3      
327XP3R3V_FPGA      R25   -1          A01X+020477Y+006320X0280Y0240R270 S1      
317XP3R3V_FPGA      VIA   -    MD0100PA00X+030900Y+016450X0200Y0200     S3      
327XP3R3V_FPGA      R287  -2          A01X+031240Y+016450X0280Y0240R180 S1      
317XP3R3V_FPGA      VIA   -    MD0100PA00X+016050Y+007150X0200Y0200     S3      
317XP3R3V_FPGA      VIA   -    MD0100PA00X+016050Y+007550X0200Y0200     S3      
317XP3R3V_FPGA      VIA   -    MD0100PA00X+018260Y+028950X0200Y0200     S3      
317XP3R3V_FPGA      VIA   -    MD0100PA00X+014010Y+030690X0200Y0200     S3      
327XP3R3V_FPGA      L24   -1          A01X+014550Y+031920X0300Y0340R270 S1      
327XP3R3V_FPGA      C306  -2   M      A01X+022180Y+029730X0280Y0240R090 S1      
327XP3R3V_FPGA      R306  -1   M      A01X+031590Y+024340X0280Y0240     S1      
327XP3R3V_FPGA      R291  -1          A01X+031590Y+023890X0280Y0240     S1      
317XP3R3V_FPGA      VIA   -    MD0100PA00X+031190Y+024340X0200Y0200     S3      
317XP3R3V_FPGA      VIA   -    MD0080PA00X+022450Y+030200X0180Y0180R270 S3      
317XP3R3V_FPGA      VIA   -    MD0100PA00X+024900Y+029030X0200Y0200     S3      
327XP3R3V_FPGA      R107  -1   M      A10X+025090Y+023750X0280Y0240R180 S2      
327XP3R3V_FPGA      U10   -5          A10X+024656Y+022870X0130Y0380R180 S2      
327XP3R3V_FPGA      C68   -1   M      A10X+024610Y+023550X0280Y0240     S2      
317XP3R3V_FPGA      VIA   -    MD0080PA00X+021280Y+028950X0180Y0180R270 S3      
327XP3R3V_FPGA      R418  -1          A01X+021730Y+029310X0280Y0240R090 S1      
327XP3R3V_FPGA      R408  -1          A01X+020830Y+029310X0280Y0240R090 S1      
327XP3R3V_FPGA      R412  -1   M      A01X+021280Y+029310X0280Y0240R090 S1      
327XP3R3V_FPGA      U35   -8          A01X+021734Y+030845X0180Y0600     S1      
327XP3R3V_FPGA      DS18  -2          A01X+000825Y+032352X0180Y0200R090 S1      
317XP3R3V_FPGA      VIA   -    MD0100PA00X+001198Y+032352X0200Y0200     S3      
317XP3R3V_FPGA      VIA   -    MD0100PA00X+007800Y+029150X0200Y0200     S3      
327XP3R3V_FPGA      R340  -1          A10X+007410Y+029150X0280Y0240     S2      
327XP3R3V_FPGA      C39   -2   M      A10X+002410Y+030750X0280Y0240R180 S2      
327XP3R3V_FPGA      U8    -8          A10X+003695Y+030284X0180Y0600R270 S2      
317XP3R3V_FPGA      VIA   -    MD0100PA00X+002410Y+031090X0200Y0200     S3      
327XP3R3V_FPGA      R337  -1   M      A10X+001990Y+029750X0280Y0240R180 S2      
317XP3R3V_FPGA      VIA   -    MD0100PA00X+001600Y+029750X0200Y0200     S3      
327XP3R3V_FPGA      R335  -1          A10X+001990Y+029250X0280Y0240R180 S2      
327XP3R3V_FPGA      R333  -1          A10X+003350Y+028290X0280Y0240R270 S2      
317XP3R3V_FPGA      VIA   -    MD0100PA00X+003740Y+028290X0200Y0200     S3      
317XP3R3V_FPGA      VIA   -    MD0100PA00X+005459Y+026687X0200Y0200     S3      
327XP3R3V_FPGA      R361  -1          A01X+005780Y+026110X0280Y0240R270 S1      
317XP3R3V_FPGA      VIA   -    MD0100PA00X+006740Y+022710X0200Y0200     S3      
327XP3R3V_FPGA      U15   -8          A01X+005768Y+023587X0380Y0120R270 S1      
327XP3R3V_FPGA      C85   -1   M      A01X+006400Y+022710X0280Y0240R270 S1      
327XP3R3V_FPGA      R281  -1   M      A10X+008500Y+024020X0280Y0240R270 S2      
327XP3R3V_FPGA      R314  -1          A10X+008960Y+024020X0280Y0240R270 S2      
317XP3R3V_FPGA      VIA   -    MD0100PA00X+008570Y+023650X0200Y0200     S3      
317XP3R3V_FPGA      VIA   -    MD0100PA00X+006770Y+024020X0200Y0200     S3      
327XP3R3V_FPGA      R282  -1          A10X+007150Y+024020X0280Y0240R270 S2      
327XP3R3V_FPGA      DS16  -2          A01X+000825Y+026644X0180Y0200R090 S1      
317XP3R3V_FPGA      VIA   -    MD0100PA00X+001196Y+026644X0200Y0200     S3      
327XP3R3V_FPGA      R381  -1          A01X+005145Y+022330X0280Y0240R090 S1      
317XP3R3V_FPGA      VIA   -    MD0100PA00X+005145Y+021990X0200Y0200     S3      
327XP3R3V_FPGA      R331  -1          A01X+005750Y+020910X0280Y0240R270 S1      
317XP3R3V_FPGA      VIA   -    MD0100PA00X+005800Y+021350X0200Y0200     S3      
327XP3R3V_FPGA      DS17  -2          A01X+000825Y+020935X0180Y0200R090 S1      
317XP3R3V_FPGA      VIA   -    MD0100PA00X+001250Y+020950X0200Y0200     S3      
327XP3R3V_FPGA      U16   -8          A01X+005768Y+017878X0380Y0120R270 S1      
327XP3R3V_FPGA      C84   -1   M      A01X+006060Y+016894X0280Y0240R270 S1      
317XP3R3V_FPGA      VIA   -    MD0100PA00X+006444Y+016894X0200Y0200     S3      
317XP3R3V_FPGA      VIA   -    MD0100PA00X+008840Y+015490X0200Y0200     S3      
327XP3R3V_FPGA      R148  -1          A10X+008500Y+015490X0280Y0240     S2      
317XP3R3V_FPGA      VIA   -    MD0080PA00X+008830Y+016390X0180Y0180R090 S3      
327XP3R3V_FPGA      R147  -1          A10X+008500Y+016390X0280Y0240     S2      
327XP3R3V_FPGA      R383  -1          A01X+005140Y+016500X0280Y0240     S1      
317XP3R3V_FPGA      VIA   -    MD0100PA00X+005140Y+016160X0200Y0200     S3      
317XP3R3V_FPGA      VIA   -    MD0100PA00X+006050Y+015200X0200Y0200     S3      
327XP3R3V_FPGA      R365  -1          A01X+005800Y+014860X0280Y0240R270 S1      
327XP3R3V_FPGA      DS14  -2          A01X+000825Y+015226X0180Y0200R090 S1      
317XP3R3V_FPGA      VIA   -    MD0100PA00X+001126Y+015226X0200Y0200     S3      
327XP3R3V_FPGA      U13   -8          A01X+005768Y+012169X0380Y0120R270 S1      
327XP3R3V_FPGA      C83   -1   M      A01X+006250Y+011260X0280Y0240R270 S1      
317XP3R3V_FPGA      VIA   -    MD0100PA00X+006250Y+011700X0200Y0200     S3      
317XP3R3V_FPGA      VIA   -    MD0100PA00X+005900Y+009650X0200Y0200R180 S3      
327XP3R3V_FPGA      R368  -1          A01X+005800Y+009260X0280Y0240R270 S1      
327XP3R3V_FPGA      R377  -1          A01X+005050Y+010839X0280Y0240R090 S1      
317XP3R3V_FPGA      VIA   -    MD0100PA00X+005050Y+010480X0200Y0200     S3      
327XP3R3V_FPGA      DS15  -2          A01X+000825Y+009518X0180Y0200R090 S1      
317XP3R3V_FPGA      VIA   -    MD0100PA00X+001250Y+009600X0200Y0200     S3      
327XP3R3V_FPGA      U19   -8          A01X+008134Y+007085X0620Y0140R270 S1      
317XP3R3V_FPGA      VIA   -    MD0100PA00X+008210Y+007930X0200Y0200R090 S3      
327XP3R3V_FPGA      C1    -1          A10X+008600Y+007910X0280Y0240R270 S2      
327XP3R3V_FPGA      R162  -1          A10X+007430Y+009110X0280Y0240R270 S2      
327XP3R3V_FPGA      R160  -1   M      A10X+007880Y+009110X0280Y0240R270 S2      
317XP3R3V_FPGA      VIA   -    MD0100PA00X+007640Y+008720X0200Y0200R090 S3      
327XP3R3V_FPGA      R1992 -1   M      A01X+012157Y+007536X0280Y0240R180 S1      
327XP3R3V_FPGA      R19   -1          A01X+012157Y+007086X0280Y0240R180 S1      
317XP3R3V_FPGA      VIA   -    MD0100PA00X+012500Y+007650X0200Y0200     S3      
327XP3R3V_FPGA      R158  -1          A10X+013090Y+007530X0280Y0240R180 S2      
327XP3R3V_FPGA      U7    -4          A01X+010705Y+006536X0200Y0470R090 S1      
317XP3R3V_FPGA      VIA   -    MD0100PA00X+011133Y+005981X0200Y0200     S3      
327XP3R3V_FPGA      C225  -1          A01X+011737Y+006136X0280Y0240     S1      
327XP3R3V_FPGA      R1991 -1          A10X+011738Y+006587X0280Y0240R180 S2      
327XP3R3V_FPGA      R3    -1          A10X+008510Y+006650X0280Y0240     S2      
317XP3R3V_FPGA      VIA   -    MD0100PA00X+008600Y+006310X0200Y0200R090 S3      
327XP3R3V_FPGA      R379  -1          A10X+005770Y+006970X0280Y0240R090 S2      
317XP3R3V_FPGA      VIA   -    MD0100PA00X+006010Y+007300X0200Y0200     S3      
327XP3R3V_FPGA      U14   -8          A01X+005768Y+006461X0380Y0120R270 S1      
317XP3R3V_FPGA      VIA   -    MD0100PA00X+005960Y+006020X0200Y0200     S3      
327XP3R3V_FPGA      C82   -1          A10X+006350Y+006150X0280Y0240R180 S2      
327XP3R3V_FPGA      C17   -1   M      A01X+015480Y+006212X0280Y0240R090 S1      
327XP3R3V_FPGA      U2    -8          A01X+016622Y+005900X0200Y0650R270 S1      
317XP3R3V_FPGA      VIA   -    MD0100PA00X+015327Y+005840X0200Y0200     S3      
327XP3R3V_FPGA      R423  -1   M      A01X+059140Y+009650X0280Y0240     S1      
327XP3R3V_FPGA      R21   -1          A01X+059140Y+010250X0280Y0240     S1      
317XP2R5V_FPGA      VIA   -    MD0080PA00X+046987Y+015482X0180Y0180     S0      
327XP2R5V_FPGA      C151  -1          A10X+046790Y+015678X0250Y0250     S2      
327XP2R5V_FPGA      U24   -AA7        A01X+046790Y+015678X0197Y0197R090 S1      
317XP2R5V_FPGA      VIA   -    MD0080PA00X+045806Y+015088X0180Y0180     S0      
327XP2R5V_FPGA      C93   -1          A10X+046003Y+015285X0250Y0250R270 S2      
327XP2R5V_FPGA      U24   -V6         A01X+045609Y+015285X0197Y0197R090 S1      
317XP2R5V_FPGA      VIA   -    MD0080PA00X+041475Y+015088X0180Y0180     S0      
327XP2R5V_FPGA      C204  -1          A10X+041672Y+015285X0250Y0250     S2      
327XP2R5V_FPGA      C146  -1          A10X+041672Y+014891X0250Y0250     S2      
327XP2R5V_FPGA      U24   -H6         A01X+041672Y+015285X0197Y0197R090 S1      
317XP2R5V_FPGA      VIA   -    MD0080PA00X+047381Y+014300X0180Y0180     S0      
327XP2R5V_FPGA      C122  -1          A10X+047667Y+014280X0250Y0250R090 S2      
327XP2R5V_FPGA      U24   -AB4        A01X+047184Y+014497X0197Y0197R090 S1      
317XP2R5V_FPGA      VIA   -    MD0080PA00X+046200Y+013907X0180Y0180     S0      
327XP2R5V_FPGA      C127  -1          A10X+046003Y+014104X0250Y0250     S2      
327XP2R5V_FPGA      U24   -W3         A01X+046003Y+014104X0197Y0197R090 S1      
317XP2R5V_FPGA      VIA   -    MD0080PA00X+045018Y+013513X0180Y0180     S0      
327XP2R5V_FPGA      C160  -1          A10X+045215Y+013710X0250Y0250R270 S2      
327XP2R5V_FPGA      U24   -T2         A01X+044822Y+013710X0197Y0197R090 S1      
317XP2R5V_FPGA      VIA   -    MD0080PA00X+044625Y+014694X0180Y0180     S0      
327XP2R5V_FPGA      C135  -1          A10X+044428Y+014497X0250Y0250R090 S2      
327XP2R5V_FPGA      U24   -R5         A01X+044428Y+014891X0197Y0197R090 S1      
317XP2R5V_FPGA      VIA   -    MD0080PA00X+043837Y+013119X0180Y0180     S0      
327XP2R5V_FPGA      C108  -1          A10X+044034Y+013316X0250Y0250R270 S2      
327XP2R5V_FPGA      U24   -N1         A01X+043641Y+013316X0197Y0197R090 S1      
317XP2R5V_FPGA      VIA   -    MD0080PA00X+043444Y+014300X0180Y0180     S0      
327XP2R5V_FPGA      C220  -1          A10X+043641Y+014497X0250Y0250R270 S2      
327XP2R5V_FPGA      C142  -1          A10X+043090Y+014453X0250Y0250R270 S2      
327XP2R5V_FPGA      U24   -M4         A01X+043247Y+014497X0197Y0197R090 S1      
317XP2R5V_FPGA      VIA   -    MD0080PA00X+041869Y+013907X0180Y0180     S0      
327XP2R5V_FPGA      C208  -1          A10X+042066Y+014104X0250Y0250R270 S2      
327XP2R5V_FPGA      U24   -J3         A01X+042066Y+014104X0197Y0197R090 S1      
327XP2R5V_FPGA      C213  -1          A10X+040491Y+013710X0250Y0250R270 S2      
317XP2R5V_FPGA      VIA   -    MD0080PA00X+040688Y+013513X0180Y0180     S0      
327XP2R5V_FPGA      U24   -F2         A01X+040885Y+013710X0197Y0197R090 S1      
327XP2R5V_FPGA      C116  -1          A10X+039183Y+012936X0280Y0240     S2      
317XP2R5V_FPGA      VIA   -    MD0080PA00X+039507Y+013119X0180Y0180     S0      
327XP2R5V_FPGA      U24   -C1         A01X+039704Y+013316X0197Y0197R090 S1      
327XP2R5V_FPGA      C168  -1   M      A10X+049990Y+012630X0380Y0540     S2      
327XP2R5V_FPGA      C292  -1   M      A01X+049990Y+012640X0380Y0540R180 S1      
317XP2R5V_FPGA      VIA   -    MD0100PA00X+050390Y+012869X0200Y0200     S3      
317XP2R5V_FPGA      VIA   -    MD0100PA00X+050386Y+012415X0200Y0200     S3      
317XP2R5V_FPGA      VIA   -    MD0100PA00X+046250Y+011700X0200Y0200     S3      
327XP2R5V_FPGA      R439  -2          A01X+045300Y+011390X0280Y0240R270 S1      
327XP2R5V_FPGA      R438  -2   M      A01X+045850Y+011390X0280Y0240R270 S1      
327XP2R5V_FPGA      R355  -2          A10X+043700Y+010790X0280Y0240R090 S2      
327XP2R5V_FPGA      R358  -2   M      A10X+044150Y+010790X0280Y0240R090 S2      
317XP2R5V_FPGA      VIA   -    MD0100PA00X+044850Y+010050X0200Y0200     S3      
317XP2R5V_FPGA      VIA   -    MD0100PA00X+036917Y+010283X0200Y0200     S3      
327XP2R5V_FPGA      C164  -1   M      A10X+037320Y+010600X0380Y0540R180 S2      
317XP2R5V_FPGA      VIA   -    MD0100PA00X+036931Y+010950X0200Y0200     S3      
327XP2R5V_FPGA      C291  -1   M      A01X+037320Y+010600X0380Y0540     S1      
317XP2R5V_FPGA      VIA   -    MD0100PA00X+060400Y+039800X0200Y0200     S3      
317XP2R5V_FPGA      TP57  -1   MD0100PA00X+054450Y+007950X0200Y0200     S2      
327XP2R5V_FPGA      R231  -1          A01X+054040Y+006900X0280Y0240     S1      
327XP2R5V_FPGA      U25   -2          A01X+055653Y+006987X0410Y0120     S1      
327XP2R5V_FPGA      C242  -1          A01X+055270Y+007920X0280Y0240     S1      
327XP2R5V_FPGA      C239  -1          A01X+054840Y+008630X0380Y0540     S1      
317XP2R5V_FPGA      VIA   -    MD0100PA00X+054940Y+008160X0200Y0200R180 S3      
317XP2R5V_FPGA      VIA   -    MD0100PA00X+054430Y+008710X0200Y0200R180 S3      
327XP2R5V_FPGA      U25   -1          A01X+055653Y+007184X0410Y0210R180 S1      
317XP2R5V_FPGA      VIA   -    MD0100PA00X+054900Y+007822X0200Y0200R180 S3      
317XP2R5V_FPGA      VIA   -    MD0100PA00X+037950Y+041750X0200Y0200     S3      
317XP2R5V_FPGA      VIA   -    MD0100PA00X+036600Y+035085X0200Y0200     S3      
317XP2R5V_FPGA      VIA   -    MD0100PA00X+031050Y+032100X0200Y0200     S3      
327XP2R5V_FPGA      R61   -2          A10X+030680Y+032100X0280Y0240R180 S2      
317XP2R5V_FPGA      VIA   -    MD0100PA00X+055500Y+040200X0200Y0200     S3      
327XP2R5V_FPGA      R139  -2          A10X+055290Y+040700X0280Y0240     S2      
327XP1R8V_VIN       U21   -9          A01X+050483Y+026873X0410Y0120R180 S1      
327XP1R8V_VIN       U21   -10         A01X+050483Y+026676X0410Y0210     S1      
317XP1R8V_VIN       VIA   -     D0100PA00X+050100Y+026350X0200Y0200     S3      
327XP1R8V_VIN       R166  -1          A01X+049600Y+025940X0280Y0240R090 S1      
327XP1R8V_VIN       L6    -2          A01X+049330Y+025200X0300Y0340R090 S1      
327XP1R8V_VIN       C186  -1          A01X+050140Y+025340X0380Y0540     S1      
327XP1R8V_VIN       C189  -1          A01X+050420Y+025970X0280Y0240     S1      
327XP1R8V_SS        U21   -6          A01X+050483Y+027464X0410Y0210R180 S1      
317XP1R8V_SS        VIA   -     D0080PA00X+050000Y+027880X0180Y0180     S3      
327XP1R8V_SS        C191  -1   M      A01X+049734Y+027770X0120Y0150R180 S1      
327XP1R8V_PG_R      U21   -4          A01X+051677Y+027267X0410Y0120R180 S1      
317XP1R8V_PG_R      VIA   -    MD0080PA00X+052260Y+027620X0180Y0180     S3      
327XP1R8V_PG_R      C193  -1   M      A01X+052696Y+027250X0120Y0150     S1      
327XP1R8V_PG_R      R182  -1          A01X+053150Y+027690X0280Y0240R090 S1      
327XP1R8V_PG_R      R179  -2   M      A01X+052700Y+027690X0280Y0240R270 S1      
327m0207            L33   -1          A01X+036820Y+022050X0300Y0340R180 S1      
317m0207            VIA   -    MD0100PA00X+037750Y+022350X0200Y0200     S3      
317m0207            VIA   -    MD0100PA00X+037750Y+022650X0200Y0200     S3      
317m0207            VIA   -    MD0100PA00X+037750Y+022100X0200Y0200     S3      
317m0207            VIA   -    MD0100PA00X+037750Y+021850X0200Y0200     S3      
327m0207            C128  -1          A10X+044231Y+017550X0280Y0240R180 S2      
327m0207            U24   -P12        A01X+044034Y+017647X0197Y0197R090 S1      
317m0207            VIA   -    MD0080PA00X+044231Y+017844X0180Y0180     S0      
317m0207            VIA   -    MD0080PA00X+044625Y+017056X0180Y0180     S0      
327m0207            C138  -1          A10X+044428Y+016860X0250Y0250R180 S2      
327m0207            U24   -R11        A01X+044428Y+017253X0197Y0197R090 S1      
327m0207            C206  -1          A10X+043641Y+018041X0250Y0250R180 S2      
317m0207            VIA   -    MD0080PA00X+043444Y+017844X0180Y0180     S0      
327m0207            U24   -M12        A01X+043247Y+017647X0197Y0197R090 S1      
327m0207            C212  -1          A10X+043650Y+017410X0280Y0240     S2      
327m0207            U24   -K12        A01X+042460Y+017647X0197Y0197R090 S1      
327m0207            C200  -1          A10X+042460Y+018041X0250Y0250     S2      
327m0207            C219  -1          A10X+042410Y+017500X0280Y0240     S2      
317m0207            VIA   -    MD0080PA00X+042263Y+017844X0180Y0180     S0      
317m0207            VIA   -    MD0080PA00X+042263Y+016663X0180Y0180     S0      
327m0207            C120  -1          A10X+042066Y+016466X0250Y0250R090 S2      
327m0207            U24   -K10        A01X+042460Y+016860X0197Y0197R090 S1      
317m0207            VIA   -    MD0080PA00X+041475Y+017844X0180Y0180     S0      
327m0207            U24   -H12        A01X+041672Y+017647X0197Y0197R090 S1      
327m0207            C113  -1          A10X+041400Y+017500X0280Y0240     S2      
327m0207            C106  -1          A10X+040491Y+018041X0250Y0250     S2      
317m0207            VIA   -    MD0080PA00X+040294Y+017844X0180Y0180     S0      
327m0207            U24   -E12        A01X+040491Y+017647X0197Y0197R090 S1      
327XP1R8V_FPGA_PG   R182  -2          A01X+053150Y+028110X0280Y0240R090 S1      
327XP1R8V_FPGA_PG   R225  -1          A10X+057750Y+007960X0280Y0240R090 S2      
317XP1R8V_FPGA_PG   TP41  -1   MD0100PA00X+057650Y+009800X0200Y0200     S2      
317XP1R8V_FPGA_PG   VIA   -    MD0080PA00X+013850Y+038750X0180Y0180R180 S3      
327XP1R8V_FPGA_PG   R226  -1   M      A10X+045660Y+029450X0280Y0240     S2      
317XP1R8V_FPGA_PG   VIA   -    MD0100PA00X+053100Y+028550X0200Y0200     S3      
317XP1R8V_FPGA_PG   VIA   -    MD0100PA00X+046080Y+029420X0200Y0200     S3      
317XP1R8V_FPGA_PG   VIA   -    MD0100PA00X+042500Y+038100X0200Y0200     S3      
327XP1R8V_FPGA_PG   R142  -1          A10X+014350Y+039010X0280Y0240R180 S2      
327XP1R8V_FPGA      L18   -1          A01X+009525Y+026320X0300Y0340R180 S1      
327XP1R8V_FPGA      C276  -1          A01X+009490Y+025805X0280Y0240R180 S1      
317XP1R8V_FPGA      VIA   -    MD0100PA00X+009900Y+026002X0200Y0200R270 S3      
317XP1R8V_FPGA      VIA   -    MD0100PA00X+009850Y+025666X0200Y0200R270 S3      
327XP1R8V_FPGA      L33   -2          A01X+036280Y+022050X0300Y0340R180 S1      
317XP1R8V_FPGA      VIA   -    MD0100PA00X+035550Y+022300X0200Y0200     S3      
317XP1R8V_FPGA      VIA   -    MD0100PA00X+035550Y+022550X0200Y0200     S3      
327XP1R8V_FPGA      C158  -1          A10X+036120Y+022300X0380Y0540R180 S2      
327XP1R8V_FPGA      C150  -1          A10X+036090Y+021700X0280Y0240R180 S2      
317XP1R8V_FPGA      VIA   -    MD0100PA00X+035550Y+022050X0200Y0200     S3      
317XP1R8V_FPGA      VIA   -    MD0100PA00X+035550Y+021800X0200Y0200     S3      
327XP1R8V_FPGA      U21   -2          A01X+051677Y+026873X0410Y0120R180 S1      
327XP1R8V_FPGA      U21   -1          A01X+051677Y+026676X0410Y0210     S1      
317XP1R8V_FPGA      TP56  -1    D0100PA00X+053450Y+025360X0200Y0200R180 S2      
317XP1R8V_FPGA      VIA   -    MD0100PA00X+052200Y+024700X0200Y0200     S3      
317XP1R8V_FPGA      VIA   -    MD0100PA00X+052540Y+024700X0200Y0200     S3      
317XP1R8V_FPGA      VIA   -    MD0100PA00X+052390Y+025710X0200Y0200     S3      
317XP1R8V_FPGA      VIA   -    MD0100PA00X+052430Y+026170X0200Y0200     S3      
327XP1R8V_FPGA      R187  -1          A01X+052780Y+026110X0280Y0240R090 S1      
327XP1R8V_FPGA      C197  -1          A01X+052040Y+025920X0280Y0240R180 S1      
327XP1R8V_FPGA      C195  -1          A01X+052280Y+025210X0380Y0540R180 S1      
327XP1R8V_FB        U21   -3          A01X+051677Y+027070X0410Y0120R180 S1      
327XP1R8V_FB        R187  -2   M      A01X+052780Y+026530X0280Y0240R090 S1      
327XP1R8V_FB        R190  -2          A01X+053280Y+026530X0280Y0240R090 S1      
317XP1R8V_FB        VIA   -    MD0080PA00X+052240Y+027070X0180Y0180     S3      
327XP1R8V_FB        R188  -2          A10X+052780Y+026530X0280Y0240R270 S2      
327XP1R8V_EN_R      U21   -7          A01X+050483Y+027267X0410Y0120R180 S1      
317XP1R8V_EN_R      VIA   -    MD0080PA00X+050050Y+027110X0180Y0180     S3      
327XP1R8V_EN_R      R174  -1          A10X+049610Y+026860X0280Y0240R270 S2      
327XP1R8V_EN_R      R141  -2          A01X+048890Y+026860X0280Y0240R270 S1      
327XP1R8V_EN_R      C187  -1   M      A01X+049610Y+026860X0280Y0240R090 S1      
327XP1R8V_EN_R      R166  -2          A01X+049600Y+026360X0280Y0240R090 S1      
327XP1R2V_VIN       L11   -2          A01X+037080Y+030990X0300Y0340     S1      
327XP1R2V_VIN       C188  -1          A01X+037970Y+030110X0280Y0240R270 S1      
327XP1R2V_VIN       C185  -1          A01X+037320Y+030180X0380Y0540R270 S1      
327XP1R2V_VIN       U20   -9          A01X+038923Y+030047X0410Y0120R090 S1      
327XP1R2V_VIN       U20   -10         A01X+038726Y+030047X0410Y0210R270 S1      
317XP1R2V_VIN       VIA   -    MD0080PA00X+037930Y+030500X0180Y0180     S3      
327XP1R2V_VIN       R177  -1          A10X+037930Y+030920X0280Y0240R180 S2      
317XP1R2V_SS        VIA   -    MD0100PA00X+039698Y+030448X0200Y0200     S3      
327XP1R2V_SS        U20   -6          A01X+039514Y+030047X0410Y0210R090 S1      
327XP1R2V_SS        C190  -1          A01X+039820Y+030796X0120Y0150R090 S1      
317XP1R2V_PG_R      VIA   -    MD0100PA00X+039480Y+028130X0200Y0200R270 S3      
327XP1R2V_PG_R      R178  -2          A01X+039260Y+026800X0280Y0240R180 S1      
327XP1R2V_PG_R      U20   -4          A01X+039317Y+028853X0410Y0120R090 S1      
327XP1R2V_PG_R      C192  -1   M      A01X+039416Y+027740X0120Y0150     S1      
327XP1R2V_PG_R      R181  -1   M      A01X+039260Y+027250X0280Y0240     S1      
317XP1R2V_FPGA_PG   TP40  -1   MD0100PA00X+048310Y+027280X0200Y0200     S2      
327XP1R2V_FPGA_PG   R181  -2          A01X+039680Y+027250X0280Y0240     S1      
327XP1R2V_FPGA_PG   R141  -1          A01X+048890Y+027280X0280Y0240R270 S1      
327XP1R2V_FPGA      C136  -1          A10X+035200Y+013760X0280Y0240R090 S2      
327XP1R2V_FPGA      L35   -2          A10X+036180Y+013950X0300Y0340     S2      
327XP1R2V_FPGA      C143  -1          A10X+034600Y+013780X0380Y0540R090 S2      
317XP1R2V_FPGA      VIA   -    MD0100PA00X+035500Y+014150X0200Y0200     S3      
317XP1R2V_FPGA      VIA   -    MD0100PA00X+035250Y+014150X0200Y0200     S3      
317XP1R2V_FPGA      VIA   -    MD0100PA00X+035000Y+014150X0200Y0200     S3      
317XP1R2V_FPGA      VIA   -    MD0100PA00X+034750Y+014150X0200Y0200     S3      
317XP1R2V_FPGA      TP55  -1   MD0100PA00X+036550Y+027950X0200Y0200R090 S2      
327XP1R2V_FPGA      R185  -1   M      A01X+038160Y+027750X0280Y0240     S1      
327XP1R2V_FPGA      U20   -2          A01X+038923Y+028853X0410Y0120R090 S1      
327XP1R2V_FPGA      C196  -1          A01X+037970Y+028490X0280Y0240R090 S1      
327XP1R2V_FPGA      U20   -1          A01X+038726Y+028853X0410Y0210R270 S1      
327XP1R2V_FPGA      C194  -1          A01X+037290Y+028040X0380Y0540R090 S1      
317XP1R2V_FPGA      VIA   -    MD0100PA00X+037450Y+027600X0200Y0200R270 S3      
317XP1R2V_FPGA      VIA   -    MD0100PA00X+037000Y+027600X0200Y0200R270 S3      
317XP1R2V_FPGA      VIA   -    MD0100PA00X+038220Y+028100X0200Y0200R270 S3      
317XP1R2V_FPGA      VIA   -    MD0100PA00X+037800Y+028100X0200Y0200R270 S3      
327XP1R2V_FB        R186  -2          A01X+038580Y+026800X0280Y0240     S1      
317XP1R2V_FB        VIA   -    MD0100PA00X+038940Y+028110X0200Y0200R270 S3      
327XP1R2V_FB        U20   -3          A01X+039120Y+028853X0410Y0120R090 S1      
327XP1R2V_FB        R185  -2   M      A01X+038580Y+027750X0280Y0240     S1      
327XP1R2V_FB        R189  -2   M      A01X+038580Y+027250X0280Y0240     S1      
327XP1R2V_EN_R      R177  -2          A10X+038350Y+030920X0280Y0240R180 S2      
327XP1R2V_EN_R      R165  -1   M      A10X+038910Y+030920X0280Y0240R180 S2      
327XP1R2V_EN_R      R140  -2          A01X+038350Y+030920X0280Y0240     S1      
327XP1R2V_EN_R      U20   -7          A01X+039317Y+030047X0410Y0120R090 S1      
317XP1R2V_EN_R      VIA   -    MD0080PA00X+039160Y+030480X0180Y0180     S3      
327XP1R2V_EN_R      C184  -1   M      A01X+038910Y+030920X0280Y0240     S1      
327XP1R0V_SW        L5    -1          A01X+055970Y+019453X1160Y1380R270 S1      
317XP1R0V_SW        VIA   -    MD0100PA00X+055890Y+020250X0200Y0200     S3      
317XP1R0V_SW        VIA   -    MD0100PA00X+055460Y+020240X0200Y0200     S3      
327XP1R0V_SW        C265  -2          A10X+055100Y+020240X0280Y0240R090 S2      
327XP1R0V_SW        C266  -1          A10X+055890Y+019800X0280Y0240R180 S2      
327XP1R0V_SW        U26   -6          A01X+055622Y+021314X0080Y1060     S1      
327XP1R0V_SW        U26   -7          A01X+055878Y+021314X0080Y1060     S1      
327XP1R0V_SS        U26   -16         A01X+055652Y+022200X0100Y0240     S1      
327XP1R0V_SS        C259  -1          A01X+056000Y+023240X0280Y0240R090 S1      
317XP1R0V_RT        VIA   -    MD0100PA00X+056994Y+022330X0200Y0200     S3      
327XP1R0V_RT        U26   -13         A01X+056291Y+022200X0200Y0240     S1      
327XP1R0V_RT        R248  -1          A01X+057290Y+022450X0280Y0240     S1      
327XP1R0V_PG        R243  -2          A10X+054310Y+022750X0280Y0240R180 S2      
327XP1R0V_PG        U26   -18         A01X+055209Y+022200X0200Y0240     S1      
317XP1R0V_PG        VIA   -    MD0080PA00X+054816Y+022803X0180Y0180R090 S3      
327XP1R0V_PG        C258  -2          A01X+055100Y+023296X0120Y0150R270 S1      
327XP1R0V_PG        R245  -2   M      A01X+054650Y+023240X0280Y0240R270 S1      
317m0208            VIA   -    MD0080PA00X+045018Y+016663X0180Y0180     S0      
327m0208            U24   -T10        A01X+044822Y+016860X0197Y0197R090 S1      
327m0208            C207  -1          A10X+045215Y+016860X0250Y0250R090 S2      
317m0208            VIA   -    MD0080PA00X+044231Y+016663X0180Y0180     S0      
327m0208            U24   -P10        A01X+044034Y+016860X0197Y0197R090 S1      
327m0208            C201  -1          A10X+044034Y+016860X0250Y0250R090 S2      
317m0208            VIA   -    MD0080PA00X+043837Y+017056X0180Y0180     S0      
327m0208            U24   -N11        A01X+043641Y+017253X0197Y0197R090 S1      
317m0208            VIA   -    MD0080PA00X+042656Y+017056X0180Y0180     S0      
327m0208            U24   -L11        A01X+042853Y+017253X0197Y0197R090 S1      
327m0208            C114  -1          A10X+043050Y+016910X0280Y0240R090 S2      
327m0208            C109  -1          A10X+042460Y+016860X0250Y0250     S2      
327m0208            C222  -1          A10X+041278Y+016860X0250Y0250R090 S2      
317m0208            VIA   -    MD0080PA00X+041475Y+016663X0180Y0180     S0      
327m0208            U24   -H10        A01X+041672Y+016860X0197Y0197R090 S1      
317m0208            VIA   -    MD0080PA00X+041869Y+017056X0180Y0180     S0      
327m0208            U24   -J11        A01X+042066Y+017253X0197Y0197R090 S1      
317m0208            VIA   -    MD0080PA00X+045018Y+015875X0180Y0180     S0      
327m0208            U24   -T8         A01X+044822Y+016072X0197Y0197R090 S1      
317m0208            VIA   -    MD0080PA00X+044625Y+016269X0180Y0180     S0      
327m0208            U24   -R9         A01X+044428Y+016466X0197Y0197R090 S1      
327m0208            C152  -1          A10X+044822Y+016072X0250Y0250R090 S2      
327m0208            C147  -1          A10X+044428Y+016466X0250Y0250R180 S2      
317m0208            VIA   -    MD0080PA00X+044625Y+015482X0180Y0180     S0      
327m0208            U24   -R7         A01X+044428Y+015678X0197Y0197R090 S1      
327m0208            C161  -1          A10X+044428Y+015678X0250Y0250R270 S2      
317m0208            VIA   -    MD0080PA00X+043837Y+015482X0180Y0180     S0      
327m0208            U24   -N7         A01X+043641Y+015678X0197Y0197R090 S1      
327m0208            C214  -1          A10X+043641Y+015678X0250Y0250R090 S2      
317m0208            VIA   -    MD0080PA00X+044231Y+015875X0180Y0180     S0      
327m0208            U24   -P8         A01X+044034Y+016072X0197Y0197R090 S1      
327m0208            C171  -1          A10X+044034Y+016072X0250Y0250R090 S2      
317m0208            VIA   -    MD0080PA00X+043444Y+015875X0180Y0180     S0      
327m0208            U24   -M8         A01X+043247Y+016072X0197Y0197R090 S1      
327m0208            C129  -1          A10X+043641Y+016072X0250Y0250R270 S2      
317m0208            VIA   -    MD0080PA00X+042656Y+015482X0180Y0180     S0      
327m0208            U24   -L7         A01X+042853Y+015678X0197Y0197R090 S1      
327m0208            C133  -1          A10X+043050Y+015490X0280Y0240R270 S2      
317m0208            VIA   -    MD0080PA00X+042263Y+015875X0180Y0180     S0      
327m0208            U24   -K8         A01X+042460Y+016072X0197Y0197R090 S1      
327m0208            C166  -1          A10X+042460Y+016072X0250Y0250R270 S2      
317m0208            VIA   -    MD0080PA00X+041475Y+015875X0180Y0180     S0      
327m0208            U24   -H8         A01X+041672Y+016072X0197Y0197R090 S1      
327m0208            C121  -1          A10X+041672Y+016072X0250Y0250R090 S2      
317m0208            VIA   -    MD0080PA00X+041869Y+016269X0180Y0180     S0      
327m0208            U24   -J9         A01X+042066Y+016466X0197Y0197R090 S1      
327m0208            C156  -1          A10X+041672Y+016466X0250Y0250R270 S2      
317m0208            VIA   -    MD0080PA00X+041869Y+015482X0180Y0180     S0      
327m0208            U24   -J7         A01X+042066Y+015678X0197Y0197R090 S1      
327m0208            C169  -1          A10X+042066Y+015285X0250Y0250R090 S2      
327m0208            C141  -1          A10X+042066Y+015678X0250Y0250R180 S2      
327m0208            L12   -1          A01X+051830Y+017250X0300Y0340     S1      
317m0208            VIA   -    MD0100PA00X+051450Y+015700X0200Y0200     S3      
317m0208            VIA   -    MD0100PA00X+051450Y+015400X0200Y0200     S3      
327m0208            C176  -1          A01X+051925Y+013450X0450Y1040     S1      
327m0208            C173  -1          A01X+052070Y+012400X0380Y0540     S1      
327m0208            C177  -1          A01X+051925Y+014700X0450Y1040     S1      
327m0208            C175  -1          A01X+051925Y+015950X0450Y1040     S1      
317m0208            VIA   -     D0100PA00X+051450Y+014400X0200Y0200     S3      
317m0208            VIA   -    MD0100PA00X+051450Y+014800X0200Y0200     S3      
317m0208            VIA   -    MD0100PA00X+051450Y+015100X0200Y0200     S3      
317XP1R0V_FPGA_PG   TP39  -1   MD0100PA00X+057600Y+024650X0200Y0200     S2      
317XP1R0V_FPGA_PG   VIA   -    MD0080PA00X+042136Y+035997X0180Y0180     S3      
327XP1R0V_FPGA_PG   R245  -1          A01X+054650Y+023660X0280Y0240R270 S1      
317XP1R0V_FPGA_PG   VIA   -    MD0100PA00X+037550Y+030920X0200Y0200     S3      
327XP1R0V_FPGA_PG   R140  -1          A01X+037930Y+030920X0280Y0240     S1      
327m0209            C131  -1          A10X+040097Y+016466X0250Y0250R090 S2      
317m0209            VIA   -    MD0080PA00X+039900Y+016663X0180Y0180     S0      
327m0209            U24   -D10        A01X+040097Y+016860X0197Y0197R090 S1      
327m0209            C118  -1          A10X+040885Y+015678X0250Y0250R180 S2      
317m0209            VIA   -    MD0080PA00X+040688Y+015482X0180Y0180     S0      
327m0209            U24   -F7         A01X+040885Y+015678X0197Y0197R090 S1      
327m0209            C111  -1          A10X+040885Y+016072X0250Y0250R180 S2      
317m0209            VIA   -    MD0080PA00X+040688Y+016269X0180Y0180     S0      
327m0209            U24   -F9         A01X+040885Y+016466X0197Y0197R090 S1      
327m0209            C105  -1          A10X+040491Y+016072X0250Y0250R270 S2      
317m0209            VIA   -    MD0080PA00X+040294Y+015875X0180Y0180     S0      
327m0209            U24   -E8         A01X+040491Y+016072X0197Y0197R090 S1      
317m0209            VIA   -    MD0080PA00X+039900Y+015088X0180Y0180     S0      
327m0209            U24   -D6         A01X+040097Y+015285X0197Y0197R090 S1      
327m0209            C124  -1          A10X+040097Y+014891X0250Y0250R090 S2      
327m0209            C218  -1          A10X+040097Y+015285X0250Y0250R270 S2      
317m0209            VIA   -    MD0100PA00X+036790Y+015423X0200Y0200     S3      
317m0209            VIA   -    MD0100PA00X+037140Y+015430X0200Y0200     S3      
317m0209            VIA   -    MD0100PA00X+037840Y+015430X0200Y0200     S3      
317m0209            VIA   -    MD0100PA00X+037490Y+015423X0200Y0200     S3      
327m0209            L34   -1          A01X+036720Y+014700X0300Y0340R180 S1      
327m0209            C137  -1          A01X+037050Y+015820X0380Y0540R090 S1      
327XP1R0V_FPGA      L34   -2          A01X+036180Y+014700X0300Y0340R180 S1      
327XP1R0V_FPGA      C148  -1          A01X+035750Y+015790X0280Y0240R090 S1      
327XP1R0V_FPGA      C155  -1          A01X+035150Y+015820X0380Y0540R090 S1      
317XP1R0V_FPGA      VIA   -    MD0100PA00X+036050Y+015450X0200Y0200     S3      
317XP1R0V_FPGA      VIA   -    MD0100PA00X+035008Y+015430X0200Y0200     S3      
317XP1R0V_FPGA      VIA   -    MD0100PA00X+035348Y+015416X0200Y0200     S3      
317XP1R0V_FPGA      VIA   -    MD0100PA00X+035700Y+015420X0200Y0200     S3      
327XP1R0V_FPGA      L12   -2          A01X+052370Y+017250X0300Y0340     S1      
327XP1R0V_FPGA      L5    -2          A01X+055970Y+017307X1160Y1380R270 S1      
317XP1R0V_FPGA      VIA   -    MD0100PA00X+054227Y+017240X0200Y0200     S3      
317XP1R0V_FPGA      VIA   -    MD0100PA00X+053977Y+017240X0200Y0200     S3      
317XP1R0V_FPGA      TP54  -1    D0100PA00X+055800Y+016150X0200Y0200     S2      
317XP1R0V_FPGA      VIA   -    MD0100PA00X+053977Y+016990X0200Y0200     S3      
317XP1R0V_FPGA      VIA   -    MD0100PA00X+053977Y+017490X0200Y0200     S3      
317XP1R0V_FPGA      VIA   -    MD0100PA00X+054227Y+016990X0200Y0200     S3      
327XP1R0V_FPGA      C178  -1          A10X+053900Y+016460X0280Y0240R090 S2      
327XP1R0V_FPGA      C268  -1          A01X+054100Y+017940X0280Y0240R090 S1      
327XP1R0V_FPGA      C269  -1          A01X+056570Y+016100X0380Y0540     S1      
327XP1R0V_FPGA      C271  -1          A01X+053900Y+016630X0380Y0540R270 S1      
327XP1R0V_FPGA      C270  -1          A01X+053500Y+017870X0380Y0540R090 S1      
327XP1R0V_FPGA      C179  -1          A10X+054000Y+017870X0380Y0540R270 S2      
327XP1R0V_FPGA      R254  -1          A01X+056540Y+024000X0280Y0240     S1      
317XP1R0V_FPGA      VIA   -    MD0100PA00X+054352Y+017497X0200Y0200     S3      
317XP1R0V_FPGA      VIA   -    MD0100PA00X+056540Y+024470X0200Y0200R090 S3      
327m0210            R251  -2          A10X+057540Y+023240X0280Y0240R090 S2      
327m0210            R252  -2   M      A10X+057000Y+023180X0300Y0340R090 S2      
317m0210            VIA   -    MD0080PA00X+056670Y+022750X0180Y0180R090 S3      
327m0210            U26   -14         A01X+056045Y+022200X0100Y0240     S1      
327m0210            C267  -2   M      A01X+056950Y+023346X0120Y0150R270 S1      
327m0210            R255  -2          A01X+057540Y+023240X0280Y0240R270 S1      
327XP1R0V_COMP      R249  -1          A10X+056000Y+023240X0280Y0240R270 S2      
317XP1R0V_COMP      VIA   -    MD0080PA00X+055950Y+022800X0180Y0180R090 S3      
327XP1R0V_COMP      U26   -15         A01X+055848Y+022200X0100Y0240     S1      
327XP1R0V_COMP      C264  -1          A01X+056400Y+023296X0120Y0150R090 S1      
327XP1R0V_BT        R250  -1          A10X+055100Y+021710X0280Y0240R090 S2      
317XP1R0V_BT        VIA   -    MD0100PA00X+054830Y+022260X0200Y0200R090 S3      
327XP1R0V_BT        U26   -1          A01X+055100Y+021924X0240Y0120     S1      
327XP1R0V_AGND      SP3   -2          A10X+056400Y+021745X0050Y0240R270 S0      
327XP1R0V_AGND      R251  -1   M      A10X+057540Y+023660X0280Y0240R090 S2      
327XP1R0V_AGND      U26   -12         A01X+056400Y+021924X0240Y0120     S1      
317XP1R0V_AGND      VIA   -    MD0100PA00X+056695Y+022000X0200Y0200R090 S3      
327XP1R0V_AGND      R248  -2          A01X+057710Y+022450X0280Y0240     S1      
317XP1R0V_AGND      VIA   -    MD0080PA00X+057710Y+022790X0180Y0180R090 S3      
317XP1R0V_AGND      VIA   -    MD0100PA00X+057890Y+023660X0200Y0200     S3      
327XP1R0V_AGND      R252  -1          A10X+057000Y+023720X0300Y0340R090 S2      
317XP1R0V_AGND      VIA   -    MD0100PA00X+056000Y+024000X0200Y0200     S3      
327XP1R0V_AGND      C259  -2   M      A01X+056000Y+023660X0280Y0240R090 S1      
327XP1R0V_AGND      C264  -2          A01X+056400Y+023504X0120Y0150R090 S1      
327XP1R0V_AGND      C263  -2          A10X+056450Y+023346X0120Y0150R090 S2      
327XP12R0V_A_PG     U1    -10         A01X+055557Y+038346X0130Y0440R180 S1      
317XP12R0V_A_PG     TP36  -1    D0100PA00X+056000Y+040100X0200Y0200     S2      
317XP12R0V_A_PG     VIA   -    MD0080PA00X+055557Y+038805X0180Y0180R270 S3      
327XP12R0V_A_PG     R13   -2   M      A01X+055590Y+039600X0280Y0240R180 S1      
327XP12R0V_A_PG     R14   -1   M      A01X+055590Y+039150X0280Y0240     S1      
327VIN_XP1R0V       L9    -2          A01X+053950Y+022290X0300Y0340R270 S1      
327VIN_XP1R0V       R247  -1          A10X+054650Y+023660X0280Y0240R090 S2      
317VIN_XP1R0V       VIA   -    MD0100PA00X+057650Y+021970X0200Y0200R090 S3      
317VIN_XP1R0V       VIA   -    MD0100PA00X+057100Y+021790X0200Y0200R090 S3      
327VIN_XP1R0V       C257  -1          A01X+057600Y+021530X0380Y0540R270 S1      
327VIN_XP1R0V       U26   -11         A01X+056291Y+021688X0450Y0160     S1      
327VIN_XP1R0V       C262  -1          A01X+057000Y+021510X0280Y0240R270 S1      
317VIN_XP1R0V       VIA   -    MD0100PA00X+054100Y+021640X0200Y0200R180 S3      
327VIN_XP1R0V       C260  -1          A01X+053850Y+021230X0380Y0540R270 S1      
327VIN_XP1R0V       U26   -2          A01X+055209Y+021688X0450Y0160     S1      
327VIN_XP1R0V       C261  -1          A01X+054500Y+021310X0280Y0240R270 S1      
317VIN_XP1R0V       VIA   -    MD0100PA00X+054580Y+021650X0200Y0200R180 S3      
317VIN_XP1R0V       VIA   -    MD0100PA00X+054650Y+024050X0200Y0200     S3      
327m0211            VIA   -    M      A10X+056435Y+023844X0300Y0300     S2      
327m0211            C263  -1          A10X+056450Y+023554X0120Y0150R090 S2      
327m0211            R249  -2          A10X+056000Y+023660X0280Y0240R270 S2      
327m0212            R247  -2          A10X+054650Y+023240X0280Y0240R090 S2      
327m0212            R244  -2   M      A10X+055100Y+023240X0280Y0240R090 S2      
327m0212            R246  -1   M      A10X+055550Y+023240X0280Y0240R270 S2      
327m0212            C256  -1          A01X+055550Y+023240X0280Y0240R090 S1      
327m0212            U26   -17         A01X+055455Y+022200X0100Y0240     S1      
317m0212            VIA   -    MD0080PA00X+055312Y+022798X0180Y0180R090 S3      
327m0213            R253  -1          A10X+056870Y+019900X0380Y0540R180 S2      
327m0213            C266  -2          A10X+056310Y+019800X0280Y0240R180 S2      
327m0214            R254  -2          A01X+056960Y+024000X0280Y0240     S1      
327m0214            R255  -1          A01X+057540Y+023660X0280Y0240R270 S1      
327m0214            C267  -1   M      A01X+056950Y+023554X0120Y0150R270 S1      
327m0215            VIA   -    M      A10X+054721Y+020980X0300Y0300     S2      
327m0215            R250  -2          A10X+055100Y+021290X0280Y0240R090 S2      
327m0215            C265  -1          A10X+055100Y+020660X0280Y0240R090 S2      
317m0216            VIA   -    MD0080PA00X+038170Y+009240X0180Y0180R090 S3      
327m0216            C249  -1          A01X+038690Y+009700X0280Y0240     S1      
327m0216            C247  -1   M      A01X+038110Y+009700X0280Y0240R180 S1      
327m0216            R236  -1          A01X+037700Y+009160X0280Y0240R270 S1      
327m0216            Y4    -6          A01X+038800Y+008978X0390Y0550R090 S1      
327m0216            L10   -1          A10X+037700Y+009170X0300Y0340R090 S2      
327m0217            L14   -1          A10X+042700Y+008320X0300Y0340R090 S2      
317m0217            VIA   -    MD0100PA00X+042500Y+008770X0200Y0200     S3      
327m0217            R235  -1          A01X+042050Y+009210X0280Y0240R270 S1      
327m0217            Y3    -6          A01X+043140Y+009063X0350Y0250R090 S1      
327m0217            C246  -1   M      A10X+042750Y+009190X0280Y0240R270 S2      
327m0217            C248  -1   M      A10X+043200Y+009190X0280Y0240R270 S2      
327m0218            R233  -2          A10X+054460Y+006900X0280Y0240R180 S2      
327m0218            R232  -2          A10X+055570Y+007050X0280Y0240R090 S2      
327m0218            R231  -2          A01X+054460Y+006900X0280Y0240     S1      
327m0218            U25   -3          A01X+055653Y+006790X0410Y0120     S1      
317m0218            VIA   -    MD0080PA00X+054950Y+006940X0180Y0180R180 S3      
317m0219            VIA   -    MD0100PA00X+054900Y+006350X0200Y0200     S3      
327m0219            C234  -1          A01X+054604Y+006350X0120Y0150R180 S1      
327m0219            R230  -1          A10X+054460Y+006400X0280Y0240     S2      
327m0219            U25   -4          A01X+055653Y+006593X0410Y0120     S1      
327m0219            R229  -2          A10X+055550Y+006500X0280Y0240R270 S2      
317m0220            VIA   -     D0080PA00X+057250Y+006030X0180Y0180R180 S3      
327m0220            U25   -6          A01X+056847Y+006396X0410Y0210     S1      
327m0220            C231  -1   M      A01X+057596Y+006090X0120Y0150     S1      
327m0221            R228  -1          A01X+057750Y+007960X0280Y0240R270 S1      
327m0221            L13   -2          A01X+057000Y+009330X0300Y0340R270 S1      
327m0221            C230  -1          A01X+056910Y+007920X0280Y0240R180 S1      
327m0221            C228  -1          A01X+056980Y+008590X0380Y0540R180 S1      
327m0221            U25   -9          A01X+056847Y+006987X0410Y0120     S1      
327m0221            U25   -10         A01X+056847Y+007184X0410Y0210R180 S1      
317m0221            VIA   -     D0080PA00X+056860Y+007600X0180Y0180R180 S3      
327m0222            R228  -2          A01X+057750Y+007540X0280Y0240R270 S1      
327m0222            U25   -7          A01X+056847Y+006593X0410Y0120     S1      
327m0222            C227  -1   M      A01X+057720Y+007000X0280Y0240R270 S1      
317m0222            VIA   -    MD0080PA00X+057287Y+006757X0180Y0180R180 S3      
327m0222            R227  -1   M      A10X+057720Y+007000X0280Y0240R090 S2      
327m0222            C293  -1          A10X+058250Y+007540X0280Y0240R270 S2      
327m0222            R225  -2   M      A10X+057750Y+007540X0280Y0240R090 S2      
327m0223            VIA   -    M      A10X+058550Y+040950X0300Y0300     S2      
327m0223            R256  -2          A10X+058110Y+041200X0280Y0240R180 S2      
327m0223            R262  -1          A10X+058110Y+040750X0280Y0240     S2      
327m0224            VIA   -    M      A10X+056173Y+040850X0300Y0300     S2      
327m0224            R108  -2          A10X+055710Y+041150X0280Y0240R180 S2      
327m0224            R139  -1          A10X+055710Y+040700X0280Y0240     S2      
327m0225            R138  -1          A10X+054350Y+041240X0280Y0240R270 S2      
317m0225            VIA   -    MD0100PA00X+053856Y+041378X0200Y0200     S3      
327m0225            DS6   -A          A01X+054350Y+041378X0310Y0310R270 S1      
327m0226            R108  -1          A10X+055290Y+041150X0280Y0240R180 S2      
317m0226            VIA   -    MD0100PA00X+054850Y+041100X0200Y0200     S3      
327m0226            DS7   -A          A01X+055532Y+041378X0310Y0310R270 S1      
327m0227            R256  -1          A10X+057690Y+041200X0280Y0240R180 S2      
317m0227            VIA   -    MD0100PA00X+057250Y+041350X0200Y0200     S3      
327m0227            DS5   -A          A01X+057894Y+041378X0310Y0310R270 S1      
327m0228            R180  -1          A10X+056750Y+041260X0280Y0240R090 S2      
317m0228            VIA   -    MD0100PA00X+056218Y+041378X0200Y0200     S3      
327m0228            DS8   -A          A01X+056713Y+041378X0310Y0310R270 S1      
317m0229            VIA   -    MD0080PA00X+053230Y+042570X0180Y0180     S3      
327m0229            R208  -1          A10X+053230Y+042010X0280Y0240R090 S2      
327m0229            DS9   -A          A01X+052830Y+042095X0310Y0310R270 S1      
327m0230            R201  -1   M      A10X+037860Y+033700X0280Y0240     S2      
327m0230            R205  -1          A10X+037860Y+034150X0280Y0240     S2      
317m0230            VIA   -    MD0080PA00X+038300Y+033350X0180Y0180R270 S3      
327m0230            U23   -3          A01X+037690Y+033350X0720Y0200R180 S1      
317m0231            VIA   -    MD0080PA00X+034150Y+032850X0180Y0180R270 S3      
327m0231            R206  -1          A10X+034640Y+032350X0280Y0240R180 S2      
327m0231            R202  -1   M      A10X+034640Y+032800X0280Y0240R180 S2      
327m0231            U23   -7          A01X+034810Y+032850X0720Y0200R180 S1      
327m0232            R200  -1   M      A10X+037860Y+032800X0280Y0240     S2      
327m0232            R204  -1          A10X+037860Y+033250X0280Y0240     S2      
317m0232            VIA   -    MD0080PA00X+038300Y+032850X0180Y0180R270 S3      
327m0232            U23   -2          A01X+037690Y+032850X0720Y0200R180 S1      
317m0233            VIA   -    MD0080PA00X+034150Y+033850X0180Y0180R270 S3      
327m0233            R203  -1          A10X+034640Y+034150X0280Y0240R180 S2      
327m0233            R199  -1   M      A10X+034640Y+033700X0280Y0240R180 S2      
327m0233            U23   -5          A01X+034810Y+033850X0720Y0200R180 S1      
317m0234            VIA   -    MD0100PA00X+048387Y+019824X0200Y0200     S3      
327m0234            R265  -2          A10X+048840Y+019750X0280Y0240     S2      
327m0234            U24   -AB18       A01X+047184Y+020009X0197Y0197R090 S1      
327m0234            R94   -2          A01X+048840Y+019750X0280Y0240R180 S1      
317m0235            VIA   -    MD0100PA00X+048029Y+020379X0200Y0200     S3      
327m0235            R95   -2          A01X+048840Y+020250X0280Y0240R180 S1      
327m0235            U24   -AA18       A01X+046790Y+020009X0197Y0197R090 S1      
317m0236            VIA   -    MD0100PA00X+049700Y+034100X0200Y0200     S3      
327m0236            R109  -1          A10X+049850Y+035040X0280Y0240R270 S2      
327m0236            R269  -2   M      A10X+050310Y+034550X0280Y0240R180 S2      
327m0236            U24   -N15        A01X+043641Y+018828X0197Y0197R090 S1      
317m0236            VIA   -    MD0080PA00X+043837Y+019025X0180Y0180     S0      
317m0237            VIA   -    MD0100PA00X+048100Y+034100X0200Y0200     S3      
327m0237            R110  -1          A10X+049350Y+035040X0280Y0240R270 S2      
317m0237            VIA   -    MD0080PA00X+044231Y+020993X0180Y0180     S2      
327m0237            U24   -P20        A01X+044034Y+020796X0197Y0197R090 S1      
327R_XP3R3V_PG      R263  -1          A10X+035520Y+041970X0280Y0240R180 S2      
327R_XP3R3V_PG      R51   -2   M      A10X+035390Y+041300X0280Y0240     S2      
317R_XP3R3V_PG      VIA   -    MD0100PA00X+034886Y+041050X0200Y0200     S3      
327R_XP3R3V_PG      C77   -2          A01X+035266Y+041210X0120Y0150R180 S1      
327R_XP3R3V_PG      U6    -18         A01X+034180Y+040661X0200Y0240R270 S1      
327m0238            R310  -2          A01X+029370Y+032590X0280Y0240     S1      
317m0238            VIA   -    MD0080PA00X+029870Y+032350X0180Y0180R090 S3      
327m0238            U4    -15         A01X+030425Y+032510X0140Y0620R270 S1      
327m0238            R144  -2          A10X+007180Y+015990X0280Y0240R180 S2      
317m0238            VIA   -    MD0080PA00X+007595Y+016420X0180Y0180R090 S3      
327m0238            R26   -2   M      A10X+008080Y+015940X0280Y0240     S2      
327m0238            R147  -2   M      A10X+008080Y+016390X0280Y0240     S2      
327m0238            R58   -2          A10X+008080Y+016840X0280Y0240     S2      
317m0239            VIA   -    MD0080PA00X+029870Y+032700X0180Y0180R090 S3      
327m0239            U4    -14         A01X+030425Y+032766X0140Y0620R270 S1      
327m0239            R311  -2          A01X+029380Y+033320X0280Y0240     S1      
317m0239            VIA   -    MD0080PA00X+007610Y+015440X0180Y0180R090 S3      
327m0239            R27   -2          A10X+008040Y+015000X0280Y0240     S2      
327m0239            R148  -2   M      A10X+008080Y+015490X0280Y0240     S2      
327m0239            R59   -2          A10X+007160Y+014950X0280Y0240R180 S2      
327m0239            R145  -2   M      A10X+007170Y+015440X0280Y0240R180 S2      
317R_FPGA_TDO       VIA   -    MD0080PA00X+045412Y+018237X0180Y0180     S0      
317R_FPGA_TDO       VIA   -    MD0100PA00X+047925Y+017846X0200Y0200     S3      
327R_FPGA_TDO       R195  -2          A10X+048840Y+018100X0280Y0240     S2      
327R_FPGA_TDO       U24   -U13        A01X+045215Y+018041X0197Y0197R090 S1      
327PUDC             R224  -2          A10X+046200Y+024190X0280Y0240R090 S2      
327PUDC             R223  -1   M      A10X+045750Y+024190X0280Y0240R270 S2      
317PUDC             VIA   -    MD0080PA00X+045412Y+021781X0180Y0180     S2      
327PUDC             U24   -U22        A01X+045215Y+021584X0197Y0197R090 S1      
317PCIE_SMDAT       VIA   -    MD0100PA00X+009550Y+014550X0200Y0200     S3      
327PCIE_SMDAT       R175  -1          A10X+013505Y+006580X0280Y0240     S2      
317PCIE_SMDAT       VIA   -    MD0100PA00X+015120Y+007519X0200Y0200     S3      
327PCIE_SMDAT       U2    -7          A01X+016622Y+006400X0200Y0650R270 S1      
327PCIE_SMDAT       R26   -1          A10X+008500Y+015940X0280Y0240     S2      
317PCIE_SMCLK       VIA   -    MD0080PA00X+018091Y+006339X0180Y0180     S3      
327PCIE_SMCLK       U2    -2          A01X+018832Y+006400X0200Y0650R270 S1      
317PCIE_SMCLK       VIA   -    MD0080PA00X+014590Y+007520X0180Y0180     S3      
327PCIE_SMCLK       R176  -1          A10X+013507Y+007080X0280Y0240     S2      
317PCIE_SMCLK       VIA   -    MD0100PA00X+009050Y+014450X0200Y0200     S3      
327PCIE_SMCLK       R27   -1          A10X+008460Y+015000X0280Y0240     S2      
317PCIE_REFCLKP     VIA   -    MD0080PA00X+024051Y+007310X0180Y0180     S3      
327PCIE_REFCLKP     C19   -2          A10X+023431Y+006259X0280Y0240R270 S2      
327PCIE_REFCLKP     R198  -1          A10X+040885Y+016860X0250Y0250     S2      
317PCIE_REFCLKP     VIA   -    MD0080PA00X+040688Y+016663X0180Y0180     S0      
327PCIE_REFCLKP     U24   -F10        A01X+040885Y+016860X0197Y0197R090 S1      
317PCIE_REFCLKN     VIA   -    MD0080PA00X+024051Y+006990X0180Y0180     S3      
327PCIE_REFCLKN     R198  -2          A10X+040491Y+016860X0250Y0250     S2      
317PCIE_REFCLKN     VIA   -    MD0080PA00X+040294Y+016663X0180Y0180     S0      
327PCIE_REFCLKN     U24   -E10        A01X+040491Y+016860X0197Y0197R090 S1      
327PCIE_REFCLKN     C23   -2          A10X+023931Y+006260X0280Y0240R270 S2      
327OSC_200M_CLKP    Y3    -4          A01X+044140Y+009063X0350Y0250R090 S1      
327OSC_200M_CLKP    C251  -1          A01X+044140Y+010310X0280Y0240R090 S1      
327OSC_200M_CLKP    R241  -1   M      A01X+044180Y+009730X0280Y0240     S1      
327OSC_200M_CLKN    C252  -1          A01X+043690Y+010310X0280Y0240R090 S1      
327OSC_200M_CLKN    Y3    -5          A01X+043640Y+009063X0350Y0250R090 S1      
327OSC_200M_CLKN    R239  -1   M      A01X+043640Y+009730X0280Y0240R180 S1      
327OSC_125M_CLKP    C253  -1          A01X+040550Y+010290X0280Y0240R090 S1      
327OSC_125M_CLKP    Y4    -4          A01X+040800Y+008978X0390Y0550R090 S1      
327OSC_125M_CLKP    R242  -1   M      A01X+040590Y+009700X0280Y0240     S1      
327OSC_125M_CLKN    C254  -1          A01X+040100Y+010290X0280Y0240R090 S1      
327OSC_125M_CLKN    Y4    -5          A01X+039800Y+008978X0390Y0550R090 S1      
327OSC_125M_CLKN    R240  -1   M      A01X+040060Y+009700X0280Y0240R180 S1      
327m0240            R358  -1          A10X+044150Y+011210X0280Y0240R090 S2      
317m0240            VIA   -    MD0080PA00X+044085Y+011660X0180Y0180     S3      
327m0240            C251  -2          A01X+044140Y+010730X0280Y0240R090 S1      
327m0240            R359  -1   M      A01X+044165Y+011230X0280Y0240     S1      
317m0240            VIA   -    MD0080PA00X+044625Y+014300X0180Y0180     S0      
327m0240            U24   -R4         A01X+044428Y+014497X0197Y0197R090 S1      
327m0240            R278  -1          A10X+044822Y+014497X0250Y0250R180 S2      
327m0241            R355  -1          A10X+043700Y+011210X0280Y0240R090 S2      
317m0241            VIA   -    MD0080PA00X+043765Y+011660X0180Y0180     S3      
327m0241            C252  -2          A01X+043690Y+010730X0280Y0240R090 S1      
327m0241            R360  -1   M      A01X+043665Y+011230X0280Y0240R180 S1      
317m0241            VIA   -    MD0080PA00X+045018Y+014300X0180Y0180     S0      
327m0241            U24   -T4         A01X+044822Y+014497X0197Y0197R090 S1      
327m0241            R278  -2          A10X+045216Y+014497X0250Y0250R180 S2      
327m0242            C253  -2          A01X+040550Y+010710X0280Y0240R090 S1      
317m0242            VIA   -    MD0080PA00X+040485Y+011610X0180Y0180     S3      
327m0242            R197  -1          A10X+040885Y+014891X0250Y0250     S2      
317m0242            VIA   -    MD0080PA00X+040688Y+015088X0180Y0180     S0      
327m0242            U24   -F6         A01X+040885Y+015285X0197Y0197R090 S1      
327m0243            C254  -2          A01X+040100Y+010710X0280Y0240R090 S1      
317m0243            VIA   -    MD0080PA00X+040165Y+011610X0180Y0180     S3      
327m0243            R197  -2          A10X+040491Y+014891X0250Y0250     S2      
317m0243            VIA   -    MD0080PA00X+040294Y+015088X0180Y0180     S0      
327m0243            U24   -E6         A01X+040491Y+015285X0197Y0197R090 S1      
317FPGA_PROGRAM_N   TP45  -1   MD0100PA00X+048200Y+021250X0200Y0200     S2      
327FPGA_PROGRAM_N   R193  -2   M      A01X+048840Y+021150X0280Y0240R180 S1      
327FPGA_PROGRAM_N   R356  -2          A01X+048840Y+020700X0280Y0240R180 S1      
317FPGA_PROGRAM_N   VIA   -    MD0080PA00X+043837Y+017844X0180Y0180     S0      
327FPGA_PROGRAM_N   U24   -N12        A01X+043641Y+017647X0197Y0197R090 S1      
317m0244            VIA   -    MD0080PA00X+035466Y+010471X0180Y0180     S3      
317m0244            VIA   -    MD0080PA00X+046987Y+014694X0180Y0180     S0      
327m0244            U24   -AA5        A01X+046790Y+014891X0197Y0197R090 S1      
327m0244            R277  -1   M      A01X+032590Y+021060X0280Y0240R270 S1      
327m0244            R83   -1          A01X+032100Y+021100X0280Y0240R180 S1      
317m0245            VIA   -    MD0080PA00X+035146Y+010471X0180Y0180     S3      
317m0245            VIA   -    MD0080PA00X+047381Y+014694X0180Y0180     S0      
327m0245            U24   -AB5        A01X+047184Y+014891X0197Y0197R090 S1      
327m0245            R277  -2   M      A01X+032590Y+020640X0280Y0240R270 S1      
327m0245            R84   -1          A01X+032100Y+020600X0280Y0240R180 S1      
317m0246            VIA   -    MD0080PA00X+034500Y+010850X0180Y0180     S3      
317m0246            VIA   -    MD0080PA00X+047381Y+013907X0180Y0180     S0      
327m0246            U24   -AB3        A01X+047184Y+014104X0197Y0197R090 S1      
327m0246            R276  -1   M      A01X+032590Y+020110X0280Y0240R270 S1      
327m0246            R85   -1          A01X+032100Y+020150X0280Y0240R180 S1      
317m0247            VIA   -    MD0080PA00X+034180Y+010850X0180Y0180     S3      
317m0247            VIA   -    MD0080PA00X+047381Y+013513X0180Y0180     S0      
327m0247            U24   -AB2        A01X+047184Y+013710X0197Y0197R090 S1      
327m0247            R276  -2   M      A01X+032590Y+019690X0280Y0240R270 S1      
327m0247            R86   -1          A01X+032100Y+019650X0280Y0240R180 S1      
317m0248            VIA   -    MD0100PA00X+034450Y+018150X0200Y0200     S3      
317m0248            VIA   -    MD0080PA00X+045806Y+019025X0180Y0180     S0      
327m0248            VIA   -    M      A10X+024950Y+020400X0300Y0300     S2      
327m0248            U10   -1   M      A10X+024656Y+021930X0130Y0380R180 S2      
327m0248            R100  -1          A10X+025400Y+022640X0280Y0240R270 S2      
327m0248            R99   -1   M      A10X+025400Y+022160X0280Y0240R090 S2      
327m0248            U24   -V15        A01X+045609Y+018828X0197Y0197R090 S1      
327m0249            R116  -2          A01X+047850Y+035040X0280Y0240R270 S1      
317m0249            VIA   -    MD0080PA00X+046593Y+019418X0180Y0180     S0      
327m0249            U24   -Y16        A01X+046396Y+019222X0197Y0197R090 S1      
317m0249            VIA   -    MD0100PA00X+047850Y+034600X0200Y0200     S3      
327FPGA_MGTAVTT     U24   -B11        A01X+039310Y+017253X0197Y0197R090 S1      
317FPGA_MGTAVTT     VIA   -    MD0080PA00X+039113Y+017056X0180Y0180     S0      
327FPGA_MGTAVTT     C205  -1          A10X+039310Y+017253X0250Y0250R270 S2      
327FPGA_MGTAVTT     C104  -1          A10X+038863Y+017450X0280Y0240     S2      
317FPGA_MGTAVTT     VIA   -    MD0100PA00X+036740Y+017440X0200Y0200     S3      
327FPGA_MGTAVTT     R196  -1          A10X+037040Y+017200X0280Y0240R180 S2      
317FPGA_MGTAVTT     VIA   -    MD0080PA00X+039507Y+015875X0180Y0180     S0      
327FPGA_MGTAVTT     U24   -C8         A01X+039704Y+016072X0197Y0197R090 S1      
327FPGA_MGTAVTT     C117  -1          A10X+039310Y+015285X0250Y0250R180 S2      
317FPGA_MGTAVTT     VIA   -    MD0080PA00X+039113Y+015482X0180Y0180     S0      
327FPGA_MGTAVTT     U24   -B7         A01X+039310Y+015678X0197Y0197R090 S1      
327FPGA_MGTAVTT     C209  -1          A10X+039310Y+016466X0250Y0250R180 S2      
317FPGA_MGTAVTT     VIA   -    MD0080PA00X+039113Y+016269X0180Y0180     S0      
327FPGA_MGTAVTT     U24   -B9         A01X+039310Y+016466X0197Y0197R090 S1      
327FPGA_MGTAVTT     C217  -1          A10X+039704Y+014497X0250Y0250R270 S2      
317FPGA_MGTAVTT     VIA   -    MD0080PA00X+039507Y+014300X0180Y0180     S0      
327FPGA_MGTAVTT     U24   -C4         A01X+039704Y+014497X0197Y0197R090 S1      
327FPGA_MGTAVTT     C110  -1          A10X+039310Y+014891X0250Y0250     S2      
317FPGA_MGTAVTT     VIA   -    MD0080PA00X+039113Y+014694X0180Y0180     S0      
327FPGA_MGTAVTT     U24   -B5         A01X+039310Y+014891X0197Y0197R090 S1      
317FPGA_MGTAVTT     VIA   -    MD0100PA00X+038200Y+014200X0200Y0200     S3      
317FPGA_MGTAVTT     VIA   -    MD0100PA00X+037900Y+014100X0200Y0200     S3      
317FPGA_MGTAVTT     VIA   -    MD0100PA00X+037400Y+014100X0200Y0200     S3      
317FPGA_MGTAVTT     VIA   -    MD0100PA00X+037650Y+014100X0200Y0200     S3      
327FPGA_MGTAVTT     L35   -1          A10X+036720Y+013950X0300Y0340     S2      
327FPGA_MGTAVTT     C125  -1          A10X+037850Y+013680X0380Y0540R090 S2      
317FPGA_M2          VIA   -    MD0080PA00X+045412Y+016269X0180Y0180     S0      
327FPGA_M2          U24   -U9         A01X+045215Y+016466X0197Y0197R090 S1      
327FPGA_M2          R222  -1          A01X+049590Y+014300X0280Y0240     S1      
317FPGA_M2          VIA   -    MD0080PA00X+049097Y+013850X0180Y0180R180 S3      
327FPGA_M2          R221  -2   M      A01X+049590Y+013850X0280Y0240R180 S1      
317FPGA_M1          VIA   -    MD0080PA00X+045412Y+016663X0180Y0180     S0      
327FPGA_M1          U24   -U10        A01X+045215Y+016860X0197Y0197R090 S1      
327FPGA_M1          R217  -2          A10X+048840Y+016300X0280Y0240     S2      
327FPGA_M1          R218  -1   M      A10X+048840Y+016750X0280Y0240R180 S2      
317FPGA_M1          VIA   -    MD0100PA00X+048400Y+016600X0200Y0200     S3      
317FPGA_M0          VIA   -    MD0100PA00X+048100Y+017250X0200Y0200     S3      
327FPGA_M0          U24   -U11        A01X+045215Y+017253X0197Y0197R090 S1      
327FPGA_M0          R212  -1   M      A01X+048840Y+017200X0280Y0240     S1      
327FPGA_M0          R211  -2          A01X+048840Y+017650X0280Y0240R180 S1      
317m0250            VIA   -    MD0080PA00X+033750Y+011940X0180Y0180R090 S3      
327m0250            R440  -1          A10X+045300Y+011810X0280Y0240R090 S2      
317m0250            VIA   -    MD0080PA00X+045413Y+012217X0180Y0180     S3      
327m0250            R439  -1          A01X+045300Y+011810X0280Y0240R270 S1      
317m0250            VIA   -    MD0080PA00X+046200Y+013119X0180Y0180     S0      
327m0250            U24   -W1         A01X+046003Y+013316X0197Y0197R090 S1      
327m0250            R275  -1          A10X+046003Y+012922X0250Y0250R180 S2      
327m0250            R87   -1          A01X+031650Y+018000X0280Y0240R180 S1      
317m0251            VIA   -    MD0080PA00X+033750Y+011620X0180Y0180R090 S3      
327m0251            R441  -1          A10X+045850Y+011810X0280Y0240R090 S2      
317m0251            VIA   -    MD0080PA00X+045733Y+012217X0180Y0180     S3      
327m0251            R438  -1          A01X+045850Y+011810X0280Y0240R270 S1      
317m0251            VIA   -    MD0080PA00X+046593Y+013119X0180Y0180     S0      
327m0251            U24   -Y1         A01X+046396Y+013316X0197Y0197R090 S1      
327m0251            R275  -2          A10X+046396Y+012922X0250Y0250R180 S2      
327m0251            R88   -1          A01X+031650Y+017500X0280Y0240R180 S1      
317FPGA_DONE        TP44  -1   MD0100PA00X+053000Y+040650X0200Y0200     S2      
327FPGA_DONE        R208  -2   M      A10X+053230Y+041590X0280Y0240R090 S2      
327FPGA_DONE        R210  -1          A10X+052730Y+041590X0280Y0240R270 S2      
317FPGA_DONE        VIA   -    MD0080PA00X+041082Y+017056X0180Y0180     S0      
327FPGA_DONE        U24   -G11        A01X+041278Y+017253X0197Y0197R090 S1      
327FPGA_BRD_REV2    R214  -1          A01X+044400Y+024190X0280Y0240R090 S1      
317FPGA_BRD_REV2    VIA   -    MD0100PA00X+043650Y+023300X0200Y0200     S3      
327FPGA_BRD_REV2    R213  -2   M      A01X+043950Y+024190X0280Y0240R270 S1      
317FPGA_BRD_REV2    VIA   -    MD0080PA00X+043837Y+020206X0180Y0180     S2      
327FPGA_BRD_REV2    U24   -N18        A01X+043641Y+020009X0197Y0197R090 S1      
317FPGA_BRD_REV1    VIA   -    MD0080PA00X+043837Y+020600X0180Y0180     S0      
327FPGA_BRD_REV1    U24   -N19        A01X+043641Y+020403X0197Y0197R090 S1      
317FPGA_BRD_REV1    VIA   -    MD0100PA00X+044850Y+023750X0200Y0200     S3      
327FPGA_BRD_REV1    R216  -1   M      A10X+044850Y+024190X0280Y0240R270 S2      
327FPGA_BRD_REV1    R215  -2          A10X+045300Y+024190X0280Y0240R090 S2      
317FPGA_BRD_REV0    VIA   -    MD0080PA00X+043837Y+020993X0180Y0180     S0      
327FPGA_BRD_REV0    VIA   -    M      A10X+043675Y+022500X0300Y0300     S2      
327FPGA_BRD_REV0    R220  -1          A10X+044400Y+024190X0280Y0240R270 S2      
327FPGA_BRD_REV0    R219  -2   M      A10X+043950Y+024190X0280Y0240R090 S2      
327FPGA_BRD_REV0    U24   -N20        A01X+043641Y+020796X0197Y0197R090 S1      
317CFGBVS           VIA   -    MD0080PA00X+045412Y+015875X0180Y0180     S0      
327CFGBVS           U24   -U8         A01X+045215Y+016072X0197Y0197R090 S1      
317CFGBVS           VIA   -    MD0080PA00X+049097Y+013350X0180Y0180R180 S3      
327CFGBVS           R194  -2          A01X+049590Y+013350X0280Y0240R180 S1      
317CCLK_0           VIA   -    MD0080PA00X+042656Y+017844X0180Y0180     S0      
317CCLK_0           VIA   -    MD0100PA00X+043650Y+023750X0200Y0200     S3      
327CCLK_0           R207  -1          A10X+043500Y+024190X0280Y0240R270 S2      
327CCLK_0           U24   -L12        A01X+042853Y+017647X0197Y0197R090 S1      
317m0252            VIA   -    MD0100PA00X+034650Y+017400X0200Y0200     S3      
317m0252            VIA   -    MD0100PA00X+034400Y+010300X0200Y0200     S3      
327m0252            R266  -2   M      A01X+035540Y+017875X0280Y0240R090 S1      
327m0252            U11   -1          A01X+035361Y+018854X0530Y0080R090 S1      
327m0252            U10   -2          A10X+024400Y+021930X0130Y0380R180 S2      
317m0252            VIA   -    MD0100PA00X+062850Y+018950X0200Y0200     S3      
327m0252            R102  -1   M      A10X+062550Y+019677X0280Y0240R270 S2      
327m0252            R101  -2          A10X+063000Y+019677X0280Y0240R090 S2      
327m0253            U9    -5          A01X+062699Y+022018X0200Y0470     S1      
317m0253            VIA   -    MD0080PA00X+062580Y+021587X0180Y0180     S3      
327m0253            J11   -1          A01X+064105Y+020591X0160Y0530R090 S1      
327m0253            R101  -1          A10X+063000Y+020097X0280Y0240R090 S2      
317m0253            VIA   -    MD0100PA00X+062750Y+020537X0200Y0200     S3      
327m0253            C63   -1          A01X+062890Y+020127X0280Y0240R270 S1      
327m0253            C61   -1          A01X+062250Y+020367X0380Y0540R270 S1      
317m0253            VIA   -    MD0080PA00X+063350Y+020591X0180Y0180     S3      
317XP5R0V_SW        VIA   -    MD0100PA00X+017700Y+039800X0200Y0200     S3      
327XP5R0V_SW        L1    -1   M      A01X+018439Y+039760X0960Y1460     S1      
327XP5R0V_SW        C45   -1          A10X+018000Y+040240X0280Y0240R270 S2      
317XP5R0V_SW        VIA   -    MD0100PA00X+017500Y+039450X0200Y0200     S3      
327XP5R0V_SW        C44   -2          A10X+017660Y+039100X0280Y0240R180 S2      
327XP5R0V_SW        U5    -6          A01X+016696Y+039532X0080Y1060R090 S1      
327XP5R0V_SW        U5    -7          A01X+016696Y+039788X0080Y1060R090 S1      
317XP5R0V_SS        VIA   -    MD0080PA00X+015315Y+039459X0180Y0180R180 S3      
327XP5R0V_SS        C31   -1          A01X+014770Y+039910X0280Y0240R180 S1      
327XP5R0V_SS        U5    -16         A01X+015810Y+039562X0100Y0240R090 S1      
317XP5R0V_RT        VIA   -    MD0100PA00X+015170Y+041130X0200Y0200     S3      
327XP5R0V_RT        R29   -1          A01X+015560Y+041200X0280Y0240R090 S1      
327XP5R0V_RT        U5    -13         A01X+015810Y+040201X0200Y0240R090 S1      
327XP5R0V_PG        R47   -2          A10X+014670Y+038510X0280Y0240R180 S2      
327XP5R0V_PG        R294  -1   M      A01X+014670Y+038510X0280Y0240R180 S1      
317XP5R0V_PG        VIA   -    MD0080PA00X+015110Y+038630X0180Y0180R180 S3      
327XP5R0V_PG        U5    -18         A01X+015810Y+039119X0200Y0240R090 S1      
327XP5R0V_PG        C75   -2          A01X+014714Y+039010X0120Y0150     S1      
327m0254            R32   -1          A10X+014770Y+041420X0280Y0240     S2      
327m0254            R34   -2          A01X+014770Y+041420X0280Y0240     S1      
317m0254            VIA   -    MD0080PA00X+015153Y+040630X0180Y0180R180 S3      
327m0254            C11   -2   M      A01X+014664Y+040860X0120Y0150     S1      
327m0254            U5    -14         A01X+015810Y+039955X0100Y0240R090 S1      
327m0254            R50   -2   M      A10X+014720Y+040900X0300Y0340R180 S2      
327XP5R0V_COMP      C43   -1          A01X+014714Y+040310X0120Y0150R180 S1      
327XP5R0V_COMP      U5    -15         A01X+015810Y+039758X0100Y0240R090 S1      
317XP5R0V_COMP      VIA   -    MD0080PA00X+015210Y+039930X0180Y0180R180 S3      
327XP5R0V_COMP      R30   -1          A10X+014770Y+039910X0280Y0240     S2      
327XP5R0V_BT        R31   -1          A10X+016240Y+038850X0280Y0240R180 S2      
317XP5R0V_BT        VIA   -    MD0100PA00X+015790Y+038740X0200Y0200R180 S3      
327XP5R0V_BT        U5    -1          A01X+016086Y+039010X0240Y0120R090 S1      
327XP5R0V_AGND      R32   -2   M      A10X+014350Y+041420X0280Y0240     S2      
327XP5R0V_AGND      SP1   -2          A10X+016265Y+040310X0050Y0240     S0      
317XP5R0V_AGND      VIA   -    MD0100PA00X+015850Y+040520X0200Y0200R180 S3      
327XP5R0V_AGND      U5    -12         A01X+016086Y+040310X0240Y0120R090 S1      
327XP5R0V_AGND      C42   -2          A10X+014770Y+040360X0280Y0240R180 S2      
317XP5R0V_AGND      VIA   -    MD0100PA00X+014350Y+041800X0200Y0200     S3      
327XP5R0V_AGND      R50   -1          A10X+014180Y+040900X0300Y0340R180 S2      
317XP5R0V_AGND      VIA   -    MD0080PA00X+015220Y+041630X0180Y0180R180 S3      
327XP5R0V_AGND      R29   -2          A01X+015560Y+041620X0280Y0240R090 S1      
317XP5R0V_AGND      VIA   -    MD0100PA00X+014000Y+040100X0200Y0200     S3      
327XP5R0V_AGND      C43   -2          A01X+014506Y+040310X0120Y0150R180 S1      
327XP5R0V_AGND      C31   -2   M      A01X+014350Y+039910X0280Y0240R180 S1      
317XP5R0V           VIA   -    MD0100PA00X+051400Y+037400X0200Y0200     S3      
317XP5R0V           VIA   -    MD0100PA00X+051750Y+037400X0200Y0200     S3      
327XP5R0V           C272  -1          A01X+051310Y+037750X0280Y0240R180 S1      
327XP5R0V           L15   -1          A01X+051200Y+038530X0300Y0340R090 S1      
317XP5R0V           VIA   -    MD0100PA00X+051800Y+038250X0200Y0200     S3      
327XP5R0V           R180  -2          A10X+056750Y+040840X0280Y0240R090 S2      
317XP5R0V           VIA   -    MD0100PA00X+056750Y+040300X0200Y0200     S3      
317XP5R0V           VIA   -    MD0100PA00X+015600Y+032900X0200Y0200     S3      
327XP5R0V           CR1   -A          A01X+015967Y+032700X0200Y0200R180 S1      
317XP5R0V           VIA   -    MD0100PA00X+015600Y+032500X0200Y0200     S3      
317XP5R0V           VIA   -    MD0100PA00X+032450Y+029550X0200Y0200     S3      
317XP5R0V           VIA   -    MD0100PA00X+032100Y+029550X0200Y0200     S3      
317XP5R0V           VIA   -    MD0100PA00X+031750Y+029550X0200Y0200     S3      
327XP5R0V           C62   -1          A10X+032450Y+029010X0280Y0240R090 S2      
327XP5R0V           L3    -2          A10X+031850Y+029070X0300Y0340R270 S2      
317XP5R0V           VIA   -    MD0100PA00X+025900Y+034450X0200Y0200     S3      
317XP5R0V           VIA   -    MD0100PA00X+025500Y+034450X0200Y0200     S3      
317XP5R0V           VIA   -    MD0100PA00X+025100Y+034450X0200Y0200     S3      
317XP5R0V           VIA   -    MD0100PA00X+024700Y+034450X0200Y0200     S3      
317XP5R0V           VIA   -    MD0100PA00X+022000Y+039600X0200Y0200     S3      
317XP5R0V           TP60  -1   MD0100PA00X+022500Y+039600X0200Y0200     S2      
327XP5R0V           C12   -1          A01X+021760Y+038870X0280Y0240R270 S1      
327XP5R0V           C13   -1          A01X+022360Y+038940X0380Y0540R270 S1      
327XP5R0V           C15   -1          A01X+022610Y+040380X0380Y0540R090 S1      
327XP5R0V           C14   -1          A01X+021860Y+040380X0380Y0540R090 S1      
317XP5R0V           VIA   -    MD0100PA00X+013510Y+041260X0200Y0200     S3      
327XP5R0V           R6    -1          A01X+013850Y+041260X0280Y0240R270 S1      
317XP5R0V           VIA   -    MD0100PA00X+021650Y+039600X0200Y0200R180 S3      
327XP5R0V           L1    -2          A01X+020781Y+039760X0960Y1460     S1      
317XP5R0V           VIA   -    MD0100PA00X+021550Y+039250X0200Y0200R180 S3      
317XP5R0V           VIA   -    MD0100PA00X+021900Y+039250X0200Y0200R180 S3      
317XP3R3V_SW        VIA   -    MD0100PA00X+032300Y+040150X0200Y0200     S3      
327XP3R3V_SW        C56   -2          A10X+032440Y+040700X0280Y0240     S2      
317XP3R3V_SW        VIA   -    MD0100PA00X+032000Y+039850X0200Y0200     S3      
327XP3R3V_SW        C57   -1          A10X+031850Y+039210X0280Y0240R090 S2      
327XP3R3V_SW        U6    -6          A01X+033294Y+040248X0080Y1060R270 S1      
327XP3R3V_SW        U6    -7          A01X+033294Y+039992X0080Y1060R270 S1      
327XP3R3V_SW        L2    -1          A01X+030500Y+039821X0960Y1460R270 S1      
327XP3R3V_SS        U6    -16         A01X+034180Y+040218X0100Y0240R270 S1      
327XP3R3V_SS        C49   -1          A01X+035220Y+039870X0280Y0240     S1      
327XP3R3V_RT        R35   -1          A01X+034430Y+038580X0280Y0240R270 S1      
327XP3R3V_RT        U6    -13         A01X+034180Y+039579X0200Y0240R270 S1      
317XP3R3V_PG        VIA   -    MD0100PA00X+059065Y+024568X0200Y0200     S3      
327XP3R3V_PG        R244  -1          A10X+055100Y+023660X0280Y0240R090 S2      
317XP3R3V_PG        TP38  -1   MD0100PA00X+037450Y+041850X0200Y0200     S2      
327XP3R3V_PG        R263  -2          A10X+035940Y+041970X0280Y0240R180 S2      
317m0255            VIA   -    MD0100PA00X+034700Y+039120X0200Y0200     S3      
327m0255            R38   -1          A01X+035360Y+037800X0280Y0240R180 S1      
327m0255            R40   -2   M      A01X+035220Y+038330X0280Y0240R180 S1      
327m0255            U6    -14         A01X+034180Y+039825X0100Y0240R270 S1      
327m0255            C16   -2   M      A01X+035276Y+038920X0120Y0150R180 S1      
327m0255            R54   -2          A10X+035160Y+038870X0300Y0340     S2      
317XP3R3V_EN        TP59  -1    D0100PA00X+036900Y+041350X0200Y0200R180 S2      
327XP3R3V_EN        U6    -17         A01X+034180Y+040415X0100Y0240R270 S1      
327XP3R3V_EN        R52   -1          A01X+035220Y+040770X0280Y0240     S1      
327XP3R3V_EN        C46   -1   M      A01X+035220Y+040320X0280Y0240     S1      
317XP3R3V_EN        VIA   -    MD0100PA00X+034828Y+040568X0200Y0200     S3      
327XP3R3V_EN        R53   -2          A10X+035220Y+040770X0280Y0240     S2      
327XP3R3V_EN        C286  -1   M      A10X+035220Y+040320X0280Y0240R180 S2      
317XP3R3V_COMP      VIA   -    MD0100PA00X+034760Y+039880X0200Y0200     S3      
327XP3R3V_COMP      U6    -15         A01X+034180Y+040022X0100Y0240R270 S1      
327XP3R3V_COMP      C55   -1          A01X+035276Y+039470X0120Y0150     S1      
327XP3R3V_COMP      R36   -1          A10X+035220Y+039870X0280Y0240R180 S2      
327XP3R3V_BT        R37   -1          A10X+033860Y+040950X0280Y0240     S2      
327XP3R3V_BT        U6    -1          A01X+033904Y+040770X0240Y0120R270 S1      
317XP3R3V_BT        VIA   -    MD0100PA00X+034370Y+040990X0200Y0200     S3      
317XP3R3V_AGND      VIA   -    MD0100PA00X+035980Y+039770X0200Y0200     S3      
327XP3R3V_AGND      C49   -2          A01X+035640Y+039870X0280Y0240     S1      
327XP3R3V_AGND      C55   -2          A01X+035484Y+039470X0120Y0150     S1      
327XP3R3V_AGND      R54   -1          A10X+035700Y+038870X0300Y0340     S2      
317XP3R3V_AGND      VIA   -    MD0100PA00X+034770Y+038160X0200Y0200     S3      
327XP3R3V_AGND      R35   -2          A01X+034430Y+038160X0280Y0240R270 S1      
327XP3R3V_AGND      R38   -2          A01X+034940Y+037800X0280Y0240R180 S1      
327XP3R3V_AGND      SP2   -2          A10X+033725Y+039470X0050Y0240R180 S0      
327XP3R3V_AGND      C54   -2          A10X+035220Y+039420X0280Y0240     S2      
317XP3R3V_AGND      VIA   -    MD0100PA00X+034050Y+039160X0200Y0200     S3      
327XP3R3V_AGND      U6    -12         A01X+033904Y+039470X0240Y0120R270 S1      
327m0256            U1    -4          A01X+055927Y+037173X0470Y0120R180 S1      
317m0256            VIA   -    MD0100PA00X+056833Y+037120X0200Y0200R270 S3      
327m0256            C4    -2          A01X+057106Y+037120X0120Y0150R180 S1      
327XP12R0V_A_SS     U1    -6          A01X+055927Y+037567X0470Y0120R180 S1      
317XP12R0V_A_SS     VIA   -    MD0100PA00X+056860Y+038070X0200Y0200R270 S3      
327XP12R0V_A_SS     C5    -1          A01X+057200Y+038070X0280Y0240     S1      
327XP12R0V_A_OV     U1    -11         A01X+055163Y+038346X0130Y0440R180 S1      
317XP12R0V_A_OV     VIA   -    MD0080PA00X+055064Y+040090X0180Y0180R270 S3      
327XP12R0V_A_OV     R12   -1   M      A01X+055064Y+039670X0280Y0240R180 S1      
327XP12R0V_A_OV     C8    -1   M      A01X+055064Y+039120X0120Y0150R180 S1      
327XP12R0V_A_OV     R11   -2          A01X+053620Y+039570X0280Y0240     S1      
327XP12R0V_A_ISET   U1    -5          A01X+055927Y+037370X0470Y0120R180 S1      
317XP12R0V_A_ISET   VIA   -    MD0100PA00X+056860Y+037600X0200Y0200R270 S3      
327XP12R0V_A_ISET   R46   -2          A01X+057200Y+037570X0280Y0240R180 S1      
327XP12R0V_A_IMON   U1    -8          A01X+055927Y+037961X0470Y0120R180 S1      
327XP12R0V_A_IMON   R10   -1          A10X+057200Y+038570X0280Y0240R180 S2      
327XP12R0V_A_IMON   C7    -1          A01X+057200Y+038570X0280Y0240     S1      
317XP12R0V_A_IMON   VIA   -    MD0100PA00X+056750Y+038650X0200Y0200R270 S3      
327XP12R0V_A_FLTB   U1    -9          A01X+055927Y+038157X0470Y0120R180 S1      
317XP12R0V_A_FLTB   TP37  -1   MD0100PA00X+057180Y+039650X0200Y0200     S2      
327XP12R0V_A_FLTB   R16   -1          A10X+057200Y+039070X0280Y0240R180 S2      
327XP12R0V_A_FLTB   R15   -2   M      A01X+057200Y+039070X0280Y0240R180 S1      
317XP12R0V_EXT      P3    -1   MD0760PA00X+060532Y+036752X1040Y1040R270 S3      
317XP12R0V_EXT      P3    -2   MD0760PA00X+060532Y+035098X1040Y1040R270 S3      
317XP12R0V_EXT      P3    -3   MD0760PA00X+060532Y+033445X1040Y1040R270 S3      
317XP12R0V_EXT      VIA   -    MD0100PA00X+008650Y+036450X0200Y0200     S3      
317XP12R0V_EXT      VIA   -    MD0100PA00X+009050Y+036450X0200Y0200     S3      
317XP12R0V_EXT      VIA   -    MD0100PA00X+009450Y+036450X0200Y0200     S3      
317XP12R0V_EXT      VIA   -    MD0100PA00X+009450Y+036900X0200Y0200     S3      
317XP12R0V_EXT      VIA   -    MD0100PA00X+009450Y+037300X0200Y0200     S3      
317XP12R0V_EXT      VIA   -    MD0100PA00X+009450Y+037650X0200Y0200     S3      
317XP12R0V_EXT      VIA   -    MD0100PA00X+008650Y+038450X0200Y0200     S3      
317XP12R0V_EXT      VIA   -    MD0100PA00X+009050Y+038450X0200Y0200     S3      
317XP12R0V_EXT      VIA   -    MD0100PA00X+009400Y+038450X0200Y0200     S3      
317XP12R0V_EXT      VIA   -    MD0100PA00X+009450Y+038050X0200Y0200     S3      
317XP12R0V_EXT      VIA   -    MD0100PA00X+008280Y+038460X0200Y0200     S3      
327XP12R0V_EXT      CR12  -2          A01X+008730Y+037360X0630Y1180     S1      
317XP12R0V_EXT      VIA   -    MD0100PA00X+008280Y+036460X0200Y0200     S3      
327XP12R0V_A_EN     U1    -1          A01X+055927Y+036583X0470Y0120R180 S1      
317XP12R0V_A_EN     TP43  -1    D0100PA00X+056600Y+034700X0200Y0200     S2      
327XP12R0V_A_EN     R4    -2   M      A01X+057200Y+034670X0280Y0240R180 S1      
327XP12R0V_A_EN     R5    -1   M      A01X+057200Y+035170X0280Y0240     S1      
327XP12R0V_A_EN     C3    -1   M      A01X+057200Y+035670X0280Y0240     S1      
317XP12R0V_A_EN     VIA   -    MD0080PA00X+056800Y+035670X0180Y0180R270 S3      
327XP12R0V_A_AVIN   U1    -12         A01X+054793Y+038157X0470Y0120R180 S1      
327XP12R0V_A_AVIN   C6    -1          A01X+053640Y+038270X0380Y0540R180 S1      
327XP12R0V_A_AVIN   R9    -2          A01X+053680Y+039020X0300Y0340     S1      
317XP12R0V_A_AVIN   VIA   -     D0100PA00X+054060Y+038630X0200Y0200     S3      
317XP12R0V          VIA   -    MD0100PA00X+034600Y+041600X0200Y0200R090 S3      
317XP12R0V          VIA   -    MD0100PA00X+034950Y+041500X0200Y0200R090 S3      
317XP12R0V          VIA   -    MD0100PA00X+035000Y+041950X0200Y0200R090 S3      
317XP12R0V          VIA   -    MD0100PA00X+035300Y+041650X0200Y0200R090 S3      
327XP12R0V          C76   -1          A01X+035520Y+041970X0280Y0240     S1      
327XP12R0V          L8    -1          A01X+034650Y+042020X0300Y0340R180 S1      
327XP12R0V          R262  -2          A10X+057690Y+040750X0280Y0240     S2      
317XP12R0V          VIA   -    MD0100PA00X+057690Y+040310X0200Y0200     S3      
317XP12R0V          VIA   -    MD0100PA00X+056440Y+039670X0200Y0200R270 S3      
327XP12R0V          R13   -1          A01X+056010Y+039600X0280Y0240R180 S1      
317XP12R0V          VIA   -    MD0100PA00X+058030Y+039070X0200Y0200R270 S3      
327XP12R0V          R15   -1          A01X+057620Y+039070X0280Y0240R180 S1      
327XP12R0V          C74   -1          A01X+014450Y+037460X0280Y0240R270 S1      
317XP12R0V          VIA   -    MD0100PA00X+014500Y+037800X0200Y0200R270 S3      
317XP12R0V          VIA   -    MD0080PA00X+014850Y+037600X0180Y0180R180 S3      
317XP12R0V          VIA   -    MD0100PA00X+014850Y+038000X0200Y0200R270 S3      
327XP12R0V          L7    -1          A01X+015340Y+037760X0300Y0340     S1      
317XP12R0V          TP52  -1   MD0100PA00X+054060Y+023460X0200Y0200R180 S2      
327XP12R0V          C255  -1          A01X+053310Y+022800X0280Y0240R270 S1      
317XP12R0V          VIA   -    MD0100PA00X+053750Y+023200X0200Y0200R180 S3      
317XP12R0V          VIA   -    MD0100PA00X+053400Y+023150X0200Y0200R180 S3      
327XP12R0V          L9    -1          A01X+053950Y+022830X0300Y0340R270 S1      
327XP12R0V          U1    -13         A01X+054793Y+037961X0470Y0120R180 S1      
327XP12R0V          U1    -14         A01X+054793Y+037764X0470Y0120R180 S1      
327XP12R0V          U1    -15         A01X+054793Y+037567X0470Y0120R180 S1      
327XP12R0V          U1    -16         A01X+054793Y+037370X0470Y0120R180 S1      
327XP12R0V          U1    -17         A01X+054793Y+037173X0470Y0120R180 S1      
327XP12R0V          U1    -18         A01X+054793Y+036976X0470Y0120R180 S1      
327XP12R0V          U1    -19         A01X+054793Y+036779X0470Y0120R180 S1      
327XP12R0V          U1    -20         A01X+054793Y+036583X0470Y0120R180 S1      
327XP12R0V          CR3   -C          A10X+053160Y+036940X0850Y1080R270 S2      
317XP12R0V          VIA   -    MD0100PA00X+054300Y+036000X0200Y0200     S3      
317XP12R0V          VIA   -    MD0100PA00X+054330Y+036510X0200Y0200     S3      
317XP12R0V          VIA   -    MD0100PA00X+054300Y+037000X0200Y0200     S3      
327XP12R0V          C9    -1          A01X+053360Y+036720X0380Y0540R090 S1      
317XP12R0V          VIA   -    MD0100PA00X+053900Y+036000X0200Y0200     S3      
317XP12R0V          VIA   -    MD0100PA00X+053930Y+036510X0200Y0200     S3      
317XP12R0V          VIA   -    MD0100PA00X+053900Y+037000X0200Y0200     S3      
327XP12R0V          C10   -1          A01X+052540Y+036720X0380Y0540R090 S1      
327XP12R0V          FU1   -2          A01X+054790Y+035690X0300Y0340R180 S1      
327VIN_XP5R0V       R49   -1          A10X+015820Y+037760X0280Y0240     S2      
327VIN_XP5R0V       L7    -2          A01X+015880Y+037760X0300Y0340     S1      
327VIN_XP5R0V       C33   -1          A01X+016500Y+040910X0280Y0240     S1      
327VIN_XP5R0V       C30   -1          A01X+016480Y+041510X0380Y0540     S1      
327VIN_XP5R0V       U5    -11         A01X+016322Y+040201X0450Y0160R090 S1      
327VIN_XP5R0V       U5    -2          A01X+016322Y+039119X0450Y0160R090 S1      
327VIN_XP5R0V       C41   -1          A01X+016700Y+038410X0280Y0240     S1      
327VIN_XP5R0V       C32   -1          A01X+016780Y+037760X0380Y0540     S1      
317VIN_XP5R0V       VIA   -    MD0100PA00X+016055Y+041340X0200Y0200R180 S3      
317VIN_XP5R0V       VIA   -    MD0100PA00X+016058Y+041000X0200Y0200R180 S3      
317VIN_XP5R0V       VIA   -    MD0080PA00X+016060Y+041740X0180Y0180R180 S3      
317VIN_XP5R0V       VIA   -    MD0100PA00X+016360Y+037860X0200Y0200R270 S3      
317VIN_XP5R0V       VIA   -    MD0100PA00X+015910Y+038260X0200Y0200R270 S3      
317VIN_XP5R0V       VIA   -    MD0080PA00X+016330Y+038290X0180Y0180R180 S3      
327VIN_XP3R3        L8    -2          A01X+034110Y+042020X0300Y0340R180 S1      
327VIN_XP3R3        C53   -1          A01X+033290Y+041370X0280Y0240R180 S1      
327VIN_XP3R3        C50   -1          A01X+033210Y+042020X0380Y0540R180 S1      
317VIN_XP3R3        VIA   -    MD0100PA00X+034080Y+041520X0200Y0200R090 S3      
317VIN_XP3R3        VIA   -    MD0100PA00X+033630Y+041920X0200Y0200R090 S3      
317VIN_XP3R3        VIA   -    MD0100PA00X+033630Y+041520X0200Y0200R090 S3      
317VIN_XP3R3        VIA   -    MD0100PA00X+033630Y+042320X0200Y0200R090 S3      
327VIN_XP3R3        U6    -2          A01X+033668Y+040661X0450Y0160R270 S1      
327VIN_XP3R3        U6    -11         A01X+033668Y+039579X0450Y0160R270 S1      
327VIN_XP3R3        C52   -1          A01X+033490Y+038870X0280Y0240R180 S1      
327VIN_XP3R3        C48   -1          A01X+033510Y+038270X0380Y0540R180 S1      
317VIN_XP3R3        VIA   -    MD0100PA00X+033930Y+038770X0200Y0200     S3      
317VIN_XP3R3        VIA   -    MD0100PA00X+033930Y+038400X0200Y0200     S3      
317VIN_XP3R3        VIA   -    MD0100PA00X+033920Y+038030X0200Y0200     S3      
327VIN_XP3R3        R53   -1          A10X+035640Y+040770X0280Y0240     S2      
317VIN_XP3R3        VIA   -    MD0100PA00X+036070Y+040620X0200Y0200     S3      
327USB_PWR_EN       Q2    -1          A10X+030535Y+022170X0390Y0550R090 S2      
327USB_PWR_EN       VIA   -    M      A10X+026650Y+020650X0300Y0300     S2      
327USB_PWR_EN       U10   -4          A10X+024144Y+022870X0130Y0380R180 S2      
327USB_PWR_EN       R100  -2   M      A10X+025400Y+023060X0280Y0240R270 S2      
327USB_PWR_EN       U12   -4          A10X+026526Y+023065X0200Y0470R180 S2      
327USB_PWR_EN       C69   -1   M      A10X+025900Y+023060X0280Y0240R090 S2      
327m0257            R40   -1          A01X+035640Y+038330X0280Y0240R180 S1      
327m0257            C16   -1   M      A01X+035484Y+038920X0120Y0150R180 S1      
327m0257            R17   -2          A01X+036230Y+038780X0280Y0240R090 S1      
327m0258            C57   -2          A10X+031850Y+038790X0280Y0240R090 S2      
327m0258            R39   -1          A10X+031850Y+038230X0380Y0540R090 S2      
327m0259            VIA   -    M      A10X+033000Y+041130X0300Y0300     S2      
327m0259            R37   -2          A10X+033440Y+040950X0280Y0240     S2      
327m0259            C56   -1          A10X+032860Y+040700X0280Y0240     S2      
327m0260            C54   -1          A10X+035640Y+039420X0280Y0240     S2      
327m0260            R36   -2          A10X+035640Y+039870X0280Y0240R180 S2      
327m0261            R33   -1          A10X+018070Y+041300X0380Y0540R180 S2      
327m0261            C45   -2          A10X+018000Y+040660X0280Y0240R270 S2      
327m0262            R34   -1          A01X+014350Y+041420X0280Y0240     S1      
317m0262            VIA   -     D0100PA00X+013520Y+040840X0200Y0200     S3      
327m0262            R6    -2   M      A01X+013850Y+040840X0280Y0240R270 S1      
327m0262            C11   -1   M      A01X+014456Y+040860X0120Y0150     S1      
327m0263            VIA   -    M      A10X+016780Y+039270X0300Y0300     S2      
327m0263            R31   -2          A10X+016660Y+038850X0280Y0240R180 S2      
327m0263            C44   -1          A10X+017240Y+039100X0280Y0240R180 S2      
327m0264            C42   -1          A10X+014350Y+040360X0280Y0240R180 S2      
327m0264            R30   -2          A10X+014350Y+039910X0280Y0240     S2      
317m0265            VIA   -    MD0080PA00X+019500Y+005455X0180Y0180     S3      
327m0265            U2    -1          A01X+018832Y+005900X0200Y0650R270 S1      
327m0265            R25   -2          A01X+020477Y+005900X0280Y0240R270 S1      
327m0265            R354  -2   M      A01X+019977Y+005900X0280Y0240R270 S1      
327m0266            U1    -2          A01X+055927Y+036779X0470Y0120R180 S1      
317m0266            VIA   -    MD0100PA00X+056810Y+036170X0200Y0200R270 S3      
327m0266            R7    -2          A01X+057200Y+036170X0280Y0240R180 S1      
327m0267            U1    -3          A01X+055927Y+036976X0470Y0120R180 S1      
317m0267            VIA   -    MD0100PA00X+056810Y+036640X0200Y0200R270 S3      
327m0267            R8    -2          A01X+057200Y+036670X0280Y0240R180 S1      
317m0268            VIA   -    MD0080PA00X+054032Y+027044X0180Y0180     S3      
327m0268            R133  -2          A10X+055020Y+027210X0280Y0240     S2      
327m0268            J14   -4          A01X+055054Y+027210X0500Y1400R090 S1      
327m0269            R492  -2          A10X+005300Y+014440X0280Y0240R090 S2      
327m0269            R156  -2          A01X+005300Y+014440X0280Y0240R270 S1      
317m0269            VIA   -    MD0100PA00X+005592Y+014054X0200Y0200     S3      
327m0269            U13   -2          A01X+005571Y+013500X0380Y0120R270 S1      
327m0270            R493  -2          A10X+005350Y+008840X0280Y0240R090 S2      
327m0270            R157  -2          A01X+005350Y+008840X0280Y0240R270 S1      
327m0270            U14   -2          A01X+005571Y+007791X0380Y0120R270 S1      
317m0270            VIA   -    MD0100PA00X+005700Y+008350X0200Y0200     S3      
327m0271            VIA   -    M      A10X+062300Y+020538X0300Y0300     S2      
327m0271            R102  -2          A10X+062550Y+020097X0280Y0240R270 S2      
327m0271            R103  -1          A10X+062100Y+020097X0280Y0240R090 S2      
317m0272            VIA   -    MD0080PA00X+035840Y+018270X0180Y0180R180 S3      
327m0272            U11   -2          A01X+035519Y+018854X0530Y0080R090 S1      
327m0272            R104  -1          A01X+036040Y+017875X0280Y0240R270 S1      
327R_XP5R0V_EN      R49   -2          A10X+015400Y+037760X0280Y0240     S2      
327R_XP5R0V_EN      U5    -17         A01X+015810Y+039365X0100Y0240R090 S1      
327R_XP5R0V_EN      C29   -1          A01X+014770Y+039460X0280Y0240R180 S1      
317R_XP5R0V_EN      VIA   -    MD0080PA00X+015350Y+039050X0180Y0180R180 S3      
327R_XP5R0V_EN      VIA   -    M      A10X+015390Y+038220X0300Y0300R180 S2      
327R_XP5R0V_EN      R48   -1          A10X+014770Y+039460X0280Y0240     S2      
327R_XP5R0V_EN      R142  -2   M      A10X+014770Y+039010X0280Y0240R180 S2      
317m0273            VIA   -    MD0080PA00X+019814Y+003650X0180Y0180     S3      
317m0273            VIA   -    MD0100PA00X+017317Y+007084X0200Y0200     S3      
327m0273            U2    -6          A01X+016622Y+006900X0200Y0650R270 S1      
327m0273            GF1   -B6         A01X+019941Y+001378X0280Y1650     S1      
317m0274            VIA   -    MD0080PA00X+019154Y+004120X0180Y0180     S3      
327m0274            GF1   -B5         A01X+019547Y+001378X0280Y1650     S1      
317m0274            VIA   -    MD0080PA00X+018039Y+007072X0180Y0180     S3      
327m0274            U2    -3          A01X+018832Y+006900X0200Y0650R270 S1      
327MUX_USB_DP       R97   -2          A01X+031610Y+018950X0280Y0240     S1      
317MUX_USB_DP       VIA   -    MD0080PA00X+032271Y+019030X0180Y0180R090 S3      
327MUX_USB_DP       R106  -1          A10X+035330Y+018865X0280Y0240R180 S2      
317MUX_USB_DP       VIA   -    MD0080PA00X+034530Y+018990X0180Y0180R180 S3      
327MUX_USB_DP       U11   -11         A01X+035060Y+019076X0080Y0370R090 S1      
327MUX_USB_DM       R98   -2          A01X+031610Y+018500X0280Y0240     S1      
317MUX_USB_DM       VIA   -    MD0080PA00X+032591Y+019030X0180Y0180R090 S3      
317MUX_USB_DM       VIA   -    MD0080PA00X+034530Y+019310X0180Y0180R180 S3      
327MUX_USB_DM       R105  -1          A10X+035330Y+019315X0280Y0240R180 S2      
327MUX_USB_DM       U11   -10         A01X+035060Y+019234X0080Y0370R090 S1      
317m0275            MAC_PI-1    D0790PA00X+012607Y+026404X1000Y1000     S3      
327m0275            R91   -1          A10X+009080Y+028310X0280Y0240R090 S2      
327XP5R0V_VCC_ANT   L15   -2          A01X+051200Y+039070X0300Y0340R090 S1      
317XP5R0V_VCC_ANT   VIA   -    MD0100PA00X+050350Y+039450X0200Y0200     S3      
327XP5R0V_VCC_ANT   C73   -1          A10X+050850Y+038960X0280Y0240R090 S2      
327XP5R0V_VCC_ANT   C78   -1          A10X+050350Y+038960X0280Y0240R090 S2      
317XP5R0V_VCC_ANT   VIA   -    MD0100PA00X+050750Y+039450X0200Y0200     S3      
327XP5R0V_VCC_ANT   P2    -1          A01X+049155Y+039083X0400Y0880R090 S1      
327XP5R0V_VCC_ANT   C72   -1          A01X+050500Y+039030X0380Y0540R270 S1      
317XP5R0V_MAC_USB   VIA   -    MD0100PA00X+029777Y+018869X0200Y0200     S3      
317XP5R0V_MAC_USB   VIA   -    MD0100PA00X+030100Y+018761X0200Y0200     S3      
327XP5R0V_MAC_USB   VIA   -           A10X+028750Y+020350X0300Y0300     S2      
327XP5R0V_MAC_USB   C66   -1          A10X+029990Y+020500X0280Y0240R180 S2      
327XP5R0V_MAC_USB   C71   -1          A10X+027900Y+021640X0280Y0240R270 S2      
327XP5R0V_MAC_USB   U12   -1          A10X+027274Y+021935X0200Y0470R180 S2      
327XP5R0V_MAC_USB   FU3   -2          A10X+028450Y+021680X0300Y0340R090 S2      
327XP5R0V_MAC_USB   C64   -1          A10X+030020Y+019450X0380Y0540R180 S2      
327XP5R0V_MAC_USB   C65   -1          A10X+029990Y+020050X0280Y0240R180 S2      
327XP5R0V_MAC_USB   P1    -6          A01X+029273Y+018896X0100Y0710R270 S1      
317XP5R0V_MAC       MAC_PI-1    D0790PA00X+028607Y+026404X1000Y1000     S3      
327XP5R0V_MAC       L3    -1          A10X+031850Y+028530X0300Y0340R270 S2      
327XP5R0V_MAC       Q3    -2          A10X+029715Y+023520X0390Y0550R270 S2      
327XP5R0V_MAC       R44   -1          A10X+029100Y+023410X0280Y0240R090 S2      
327XP5R0V_MAC       U12   -5          A10X+027274Y+023065X0200Y0470R180 S2      
327XP5R0V_MAC       R357  -1          A10X+028500Y+023430X0380Y0540R090 S2      
327XP5R0V_MAC       C58   -1          A10X+029600Y+028470X0380Y0540R270 S2      
327XP5R0V_MAC       C282  -1          A10X+030350Y+028470X0380Y0540R270 S2      
327XP5R0V_MAC       C283  -1          A10X+031100Y+028470X0380Y0540R270 S2      
327XP5R0V_MAC       C59   -1          A10X+028550Y+028440X0280Y0240R270 S2      
327XP5R0V_MAC       C60   -1          A10X+029000Y+028440X0280Y0240R270 S2      
327XP5R0V_MAC       C70   -1          A10X+027900Y+023380X0280Y0240R090 S2      
327XP3R3V_PCIE      C289  -1          A10X+021550Y+006140X0280Y0240R270 S2      
327XP3R3V_PCIE      C290  -1          A10X+022000Y+006140X0280Y0240R270 S2      
327XP3R3V_PCIE      L21   -1          A10X+022600Y+006230X0300Y0340R270 S2      
317XP3R3V_PCIE      VIA   -    MD0080PA00X+021050Y+003050X0180Y0180     S3      
327XP3R3V_PCIE      GF1   -B8         A01X+020728Y+001378X0280Y1650     S1      
327XP3R3V_PCIE      GF1   -A9         A10X+021122Y+001378X0280Y1650     S2      
327XP3R3V_PCIE      GF1   -A10        A10X+021516Y+001378X0280Y1650     S2      
317XP3R3V_PCIE      VIA   -    MD0100PA00X+022350Y+005825X0200Y0200     S3      
317XP3R3V_PCIE      VIA   -    MD0100PA00X+034050Y+006350X0200Y0200     S3      
317XP3R3V_PCIE      VIA   -    MD0100PA00X+052950Y+006050X0200Y0200     S3      
317XP3R3V_PCIE      VIA   -    MD0100PA00X+059100Y+040400X0200Y0200     S3      
327XP3R3V_PCIE      R118  -2          A10X+059100Y+040890X0280Y0240R090 S2      
317m0276            VIA   -    MD0100PA00X+021350Y+005400X0200Y0200     S3      
327m0276            C287  -1          A01X+021050Y+005940X0280Y0240R090 S1      
327m0276            C288  -1   M      A01X+021500Y+005940X0280Y0240R090 S1      
327m0276            GF1   -B10        A01X+021516Y+001378X0280Y1650     S1      
317m0276            VIA   -    MD0100PA00X+052150Y+006000X0200Y0200     S3      
317m0276            VIA   -    MD0100PA00X+060250Y+040400X0200Y0200     S3      
327m0276            R119  -2          A10X+060250Y+040890X0280Y0240R090 S2      
317m0276            VIA   -    MD0100PA00X+033600Y+006106X0200Y0200     S3      
317XP3R3V           VIA   -    MD0100PA00X+009600Y+024100X0200Y0200     S3      
317XP3R3V           VIA   -    MD0100PA00X+006800Y+023550X0200Y0200     S3      
327XP3R3V           C312  -1   M      A01X+007150Y+024020X0280Y0240R090 S1      
327XP3R3V           U32   -8          A01X+007826Y+024275X0180Y0600R180 S1      
317XP3R3V           VIA   -    MD0100PA00X+023800Y+034500X0200Y0200     S3      
317XP3R3V           VIA   -    MD0100PA00X+014100Y+037950X0200Y0200R180 S3      
327XP3R3V           C18   -1          A01X+032550Y+036640X0280Y0240R090 S1      
327XP3R3V           R17   -1          A01X+036230Y+038360X0280Y0240R090 S1      
317XP3R3V           VIA   -    MD0100PA00X+034450Y+036130X0200Y0200     S3      
317XP3R3V           VIA   -    MD0100PA00X+033650Y+036130X0200Y0200     S3      
327XP3R3V           C20   -1   M      A01X+034800Y+036520X0380Y0540R090 S1      
327XP3R3V           C22   -1          A01X+034000Y+036520X0380Y0540R090 S1      
317XP3R3V           VIA   -    MD0100PA00X+032500Y+036300X0200Y0200     S3      
317XP3R3V           VIA   -    MD0100PA00X+033250Y+036130X0200Y0200     S3      
317XP3R3V           VIA   -    MD0100PA00X+034050Y+036130X0200Y0200     S3      
317XP3R3V           VIA   -    MD0100PA00X+034842Y+036130X0200Y0200     S3      
327XP3R3V           L2    -2          A01X+030500Y+037479X0960Y1460R270 S1      
327XP3R3V           C21   -1          A01X+033200Y+036520X0380Y0540R090 S1      
317XP3R3V           VIA   -    MD0100PA00X+036450Y+041350X0200Y0200     S3      
327XP3R3V           R47   -1          A10X+014250Y+038510X0280Y0240R180 S2      
327XP3R3V           R51   -1          A10X+035810Y+041300X0280Y0240     S2      
317XP3R3V           VIA   -    MD0100PA00X+036550Y+030590X0200Y0200     S3      
317XP3R3V           VIA   -    MD0100PA00X+036140Y+030990X0200Y0200     S3      
317XP3R3V           VIA   -    MD0100PA00X+036140Y+030580X0200Y0200     S3      
317XP3R3V           VIA   -    MD0100PA00X+036140Y+030150X0200Y0200     S3      
327XP3R3V           C180  -1          A10X+036620Y+030180X0380Y0540R090 S2      
327XP3R3V           L11   -1          A01X+036540Y+030990X0300Y0340     S1      
327XP3R3V           C182  -1          A01X+036620Y+030180X0280Y0240R270 S1      
317XP3R3V           VIA   -    MD0100PA00X+052360Y+028110X0200Y0200     S3      
327XP3R3V           R179  -1          A01X+052700Y+028110X0280Y0240R270 S1      
327XP3R3V           U22   -1          A01X+044198Y+028243X0330Y0170R180 S1      
327XP3R3V           U22   -3   M      A01X+044198Y+028662X0330Y0120R180 S1      
327XP3R3V           U22   -13  M      A01X+043560Y+028760X0710Y0960R180 S0      
317XP3R3V           VIA   -    MD0100PA00X+043305Y+029140X0200Y0200R180 S3      
317XP3R3V           VIA   -    MD0100PA00X+043815Y+028380X0200Y0200R180 S3      
317XP3R3V           TP53  -1    D0100PA00X+042900Y+027400X0200Y0200     S2      
327XP3R3V           C232  -1          A01X+044550Y+027380X0380Y0540R270 S1      
327XP3R3V           C233  -1          A01X+043900Y+027410X0280Y0240R270 S1      
317XP3R3V           VIA   -    MD0100PA00X+044560Y+027830X0200Y0200     S3      
317XP3R3V           VIA   -    MD0100PA00X+043550Y+027450X0200Y0200     S3      
317XP3R3V           VIA   -    MD0100PA00X+043460Y+027830X0200Y0200     S3      
317XP3R3V           VIA   -    MD0100PA00X+044000Y+027850X0200Y0200     S3      
317XP3R3V           VIA   -    MD0100PA00X+040000Y+026550X0200Y0200     S3      
327XP3R3V           R178  -1          A01X+039680Y+026800X0280Y0240R180 S1      
327XP3R3V           R260  -1          A10X+045660Y+027950X0280Y0240     S2      
327XP3R3V           C235  -1          A01X+045240Y+028950X0280Y0240     S1      
327XP3R3V           C181  -1          A10X+050140Y+024540X0380Y0540R180 S2      
317XP3R3V           VIA   -    MD0100PA00X+050220Y+024070X0200Y0200R090 S3      
317XP3R3V           VIA   -    MD0100PA00X+049230Y+024080X0200Y0200R090 S3      
317XP3R3V           VIA   -    MD0100PA00X+049720Y+024060X0200Y0200R090 S3      
317XP3R3V           VIA   -    MD0100PA00X+049710Y+024470X0200Y0200R090 S3      
327XP3R3V           L6    -1          A01X+049330Y+024660X0300Y0340R090 S1      
327XP3R3V           C183  -1          A01X+050140Y+024740X0280Y0240     S1      
317XP3R3V           VIA   -    MD0100PA00X+052871Y+022750X0200Y0200     S3      
327XP3R3V           R243  -1          A10X+053890Y+022750X0280Y0240R180 S2      
327XP3R3V           C226  -1          A01X+056400Y+009860X0280Y0240R270 S1      
327XP3R3V           L13   -1          A01X+057000Y+009870X0300Y0340R270 S1      
317XP3R3V           VIA   -    MD0100PA00X+056253Y+010200X0200Y0200     S3      
317XP3R3V           VIA   -    MD0100PA00X+056593Y+010200X0200Y0200     S3      
327XP3R3V           C224  -1          A01X+055750Y+009980X0380Y0540R270 S1      
317XP3R3V           VIA   -    MD0080PA00X+038040Y+008160X0180Y0180R090 S3      
327XP3R3V           L10   -2          A10X+037700Y+008630X0300Y0340R090 S2      
327XP3R3V           C245  -1   M      A10X+037700Y+008110X0280Y0240R090 S2      
327XP3R3V           C244  -1   M      A10X+042690Y+007300X0280Y0240R180 S2      
327XP3R3V           L14   -2          A10X+042700Y+007780X0300Y0340R090 S2      
317XP3R3V           VIA   -    MD0100PA00X+042300Y+007295X0200Y0200     S3      
327XP3R3V           L21   -2          A10X+022600Y+006770X0300Y0340R270 S2      
317XP3R3V           VIA   -    MD0100PA00X+023100Y+007150X0200Y0200     S3      
317XP3R3V           VIA   -    MD0100PA00X+023100Y+006800X0200Y0200     S3      
317XP3R3V           VIA   -    MD0100PA00X+025950Y+005470X0200Y0200     S3      
327XP3R3V           R56   -1          A01X+025950Y+006050X0280Y0240     S1      
317XP12R0V_PCIE     VIA   -    MD0080PA00X+018760Y+002890X0180Y0180     S3      
317XP12R0V_PCIE     VIA   -    MD0080PA00X+018600Y+003300X0180Y0180     S3      
327XP12R0V_PCIE     GF1   -B3         A01X+018760Y+001378X0280Y1650     S1      
327XP12R0V_PCIE     GF1   -B2         A01X+018366Y+001378X0280Y1650     S1      
327XP12R0V_PCIE     GF1   -B1         A01X+017972Y+001378X0280Y1650     S1      
327XP12R0V_PCIE     GF1   -A2         A10X+018366Y+001378X0280Y1650     S2      
327XP12R0V_PCIE     GF1   -A3         A10X+018760Y+001378X0280Y1650     S2      
317XP12R0V_PCIE     VIA   -    MD0080PA00X+018950Y+003300X0180Y0180     S3      
317XP12R0V_PCIE     VIA   -    MD0080PA00X+018760Y+003690X0180Y0180     S3      
327XP12R0V_PCIE     L20   -1          A01X+005710Y+038450X0300Y0340R090 S1      
327XP12R0V_PCIE     CR12  -1          A01X+006930Y+037360X0630Y1180     S1      
317XP12R0V_PCIE     VIA   -    MD0100PA00X+007050Y+038200X0200Y0200     S3      
317XP12R0V_PCIE     VIA   -    MD0100PA00X+006650Y+038200X0200Y0200     S3      
317XP12R0V_PCIE     VIA   -    MD0100PA00X+006250Y+038200X0200Y0200     S3      
317XP12R0V_PCIE     VIA   -    MD0100PA00X+006250Y+037800X0200Y0200     S3      
317XP12R0V_PCIE     VIA   -    MD0100PA00X+006250Y+037300X0200Y0200     S3      
317XP12R0V_PCIE     VIA   -    MD0100PA00X+006600Y+036500X0200Y0200     S3      
317XP12R0V_PCIE     VIA   -    MD0100PA00X+006950Y+036500X0200Y0200     S3      
317XP12R0V_PCIE     VIA   -    MD0100PA00X+007300Y+036500X0200Y0200     S3      
317XP12R0V_PCIE     VIA   -    MD0100PA00X+006250Y+036900X0200Y0200     S3      
317XP12R0V_PCIE     VIA   -    MD0100PA00X+006250Y+036500X0200Y0200     S3      
327m0277            C51   -1          A01X+036367Y+023916X0120Y0150R090 S1      
327m0277            R168  -1          A10X+034700Y+023760X0280Y0240R090 S2      
317m0277            VIA   -    MD0100PA00X+035100Y+023700X0200Y0200     S3      
327m0277            U29   -27         A01X+034515Y+023632X0270Y0100     S1      
327m0277            Y1    -2   M      A01X+035700Y+023856X0330Y0550R090 S1      
327m0278            VIA   -    M      A10X+006180Y+030250X0300Y0300     S2      
327m0278            U8    -1          A10X+005505Y+030284X0180Y0600R270 S2      
327m0278            R332  -2          A10X+006600Y+030140X0280Y0240R090 S2      
317m0279            VIA   -    MD0100PA00X+002900Y+029150X0200Y0200     S3      
327m0279            U8    -5          A10X+003695Y+029516X0180Y0600R270 S2      
327m0279            R334  -1   M      A10X+002900Y+028710X0280Y0240R090 S2      
327m0279            R333  -2          A10X+003350Y+028710X0280Y0240R270 S2      
317m0280            VIA   -    MD0100PA00X+002800Y+029650X0200Y0200     S3      
327m0280            R336  -1          A10X+002410Y+028750X0280Y0240     S2      
327m0280            U8    -6          A10X+003695Y+029772X0180Y0600R270 S2      
327m0280            R335  -2   M      A10X+002410Y+029250X0280Y0240R180 S2      
317m0281            VIA   -    MD0100PA00X+002850Y+030200X0200Y0200     S3      
327m0281            U8    -7          A10X+003695Y+030028X0180Y0600R270 S2      
327m0281            R337  -2          A10X+002410Y+029750X0280Y0240R180 S2      
327m0281            R338  -1   M      A10X+002410Y+030250X0280Y0240     S2      
317m0282            VIA   -    MD0080PA00X+029770Y+033510X0180Y0180R090 S3      
327m0282            U4    -13         A01X+030425Y+033022X0140Y0620R270 S1      
327m0282            R151  -2   M      A10X+030260Y+033500X0280Y0240     S2      
327m0282            R154  -2          A10X+030260Y+033050X0280Y0240     S2      
327m0283            R150  -2          A10X+032980Y+033400X0280Y0240R180 S2      
327m0283            R153  -2   M      A10X+032980Y+032950X0280Y0240R180 S2      
317m0283            VIA   -    MD0080PA00X+033652Y+032550X0180Y0180R090 S3      
327m0283            U4    -2          A01X+032815Y+032510X0140Y0620R270 S1      
317m0284            VIA   -    MD0080PA00X+033652Y+032050X0180Y0180R090 S3      
327m0284            U4    -1          A01X+032815Y+032254X0140Y0620R270 S1      
327m0284            R152  -2          A10X+032980Y+032500X0280Y0240R180 S2      
327m0284            R149  -2   M      A10X+032980Y+032050X0280Y0240R180 S2      
317m0285            VIA   -    MD0080PA00X+018062Y+007789X0180Y0180R090 S3      
327m0285            R23   -2          A10X+018646Y+006442X0280Y0240R270 S2      
327m0285            GF1   -B31        A01X+030571Y+001573X0280Y1260     S1      
317m0285            VIA   -    MD0080PA00X+030730Y+006130X0180Y0180     S3      
317m0286            VIA   -    MD0080PA00X+025453Y+003390X0180Y0180     S3      
327m0286            GF1   -B17        A01X+025059Y+001378X0280Y1650     S1      
317m0286            VIA   -    MD0080PA00X+025270Y+004400X0180Y0180     S3      
327m0286            R22   -2          A01X+025112Y+005840X0280Y0240R270 S1      
327m0287            R261  -1          A10X+057900Y+042610X0280Y0240R090 S2      
317m0287            VIA   -    MD0100PA00X+057399Y+042756X0200Y0200     S3      
327m0287            DS4   -A          A01X+057894Y+042756X0310Y0310R270 S1      
327m0288            R257  -1          A10X+054350Y+042610X0280Y0240R090 S2      
317m0288            VIA   -    MD0100PA00X+053856Y+042756X0200Y0200     S3      
327m0288            DS1   -A          A01X+054350Y+042756X0310Y0310R270 S1      
327m0289            R258  -1          A10X+055550Y+042610X0280Y0240R090 S2      
317m0289            VIA   -    MD0100PA00X+055037Y+042756X0200Y0200     S3      
327m0289            DS2   -A          A01X+055532Y+042756X0310Y0310R270 S1      
327m0290            R259  -1          A10X+056700Y+042610X0280Y0240R090 S2      
317m0290            VIA   -    MD0100PA00X+056218Y+042756X0200Y0200     S3      
327m0290            DS3   -A          A01X+056713Y+042756X0310Y0310R270 S1      
327SHT3X_I2C_SDA    U4    -6          A01X+032815Y+033534X0140Y0620R270 S1      
327SHT3X_I2C_SDA    R66   -1          A01X+059190Y+019086X0280Y0240R090 S1      
317SHT3X_I2C_SDA    VIA   -    MD0100PA00X+058750Y+019000X0200Y0200     S3      
317SHT3X_I2C_SDA    VIA   -    MD0100PA00X+038650Y+036500X0200Y0200     S3      
327SHT3X_I2C_SDA    R64   -2          A10X+059190Y+019506X0280Y0240R270 S2      
327SHT3X_I2C_SCL    U4    -7          A01X+032815Y+033790X0140Y0620R270 S1      
317SHT3X_I2C_SCL    VIA   -    MD0100PA00X+060690Y+018600X0200Y0200     S3      
327SHT3X_I2C_SCL    R65   -2          A10X+060690Y+019086X0280Y0240R090 S2      
327SHT3X_I2C_SCL    R67   -1          A01X+060690Y+019086X0280Y0240R090 S1      
317SHT3X_I2C_SCL    VIA   -    MD0100PA00X+038100Y+036500X0200Y0200     S3      
327SHT3X_ADDR       U27   -2          A01X+059802Y+020442X0410Y0120R090 S1      
327SHT3X_ADDR       R69   -1          A10X+059690Y+019506X0280Y0240R090 S2      
317SHT3X_ADDR       VIA   -    MD0080PA00X+059700Y+019990X0180Y0180R180 S3      
327SHT3X_ADDR       R68   -2          A01X+059690Y+019506X0280Y0240R090 S1      
327SG               R8    -1          A01X+057620Y+036670X0280Y0240R180 S1      
317SG               VIA   -    MD0100PA00X+046200Y+022450X0200Y0200     S3      
317SG               VIA   -    MD0100PA00X+058010Y+036670X0200Y0200     S3      
317SG               VIA   -    MD0100PA00X+038000Y+020450X0200Y0200     S3      
317SG               VIA   -    MD0100PA00X+012750Y+029050X0200Y0200     S3      
317SG               VIA   -    MD0100PA00X+050610Y+028060X0200Y0200     S3      
327SG               C125  -2          A10X+037850Y+013020X0380Y0540R090 S2      
327SG               C137  -2          A01X+037050Y+016480X0380Y0540R090 S1      
327SG               C155  -2          A01X+035150Y+016480X0380Y0540R090 S1      
327SG               C148  -2          A01X+035750Y+016210X0280Y0240R090 S1      
327SG               C136  -2          A10X+035200Y+013340X0280Y0240R090 S2      
327SG               C143  -2          A10X+034600Y+013120X0380Y0540R090 S2      
317SG               VIA   -    MD0100PA00X+039950Y+012000X0200Y0200     S3      
317SG               VIA   -    MD0100PA00X+040700Y+012000X0200Y0200     S3      
317SG               VIA   -    MD0080PA00X+040805Y+011610X0180Y0180     S3      
317SG               VIA   -    MD0080PA00X+040920Y+010050X0180Y0180R090 S3      
317SG               VIA   -    MD0100PA00X+041350Y+008850X0200Y0200R090 S3      
317SG               VIA   -    MD0080PA00X+041362Y+007500X0180Y0180R090 S3      
317SG               VIA   -    MD0080PA00X+041340Y+005420X0180Y0180     S3      
317SG               VIA   -    MD0080PA00X+040940Y+005420X0180Y0180     S3      
317SG               VIA   -    MD0080PA00X+040540Y+005420X0180Y0180     S3      
317SG               VIA   -    MD0080PA00X+040140Y+005420X0180Y0180     S3      
317SG               VIA   -    MD0100PA00X+029850Y+018450X0200Y0200     S3      
317SG               VIA   -    MD0080PA00X+028450Y+019070X0180Y0180     S3      
317SG               VIA   -    MD0080PA00X+028450Y+018110X0180Y0180     S3      
317SG               VIA   -    MD0100PA00X+028220Y+017912X0200Y0200     S3      
317SG               VIA   -    MD0100PA00X+027100Y+018450X0200Y0200     S3      
317SG               VIA   -    MD0100PA00X+022000Y+006900X0200Y0200     S3      
327SG               C290  -2          A10X+022000Y+006560X0280Y0240R270 S2      
317SG               VIA   -    MD0100PA00X+021500Y+006900X0200Y0200     S3      
327SG               C289  -2          A10X+021550Y+006560X0280Y0240R270 S2      
327SG               C287  -2          A01X+021050Y+006360X0280Y0240R090 S1      
327SG               C288  -2   M      A01X+021500Y+006360X0280Y0240R090 S1      
317SG               VIA   -    MD0100PA00X+019216Y+007784X0200Y0200     S3      
317SG               VIA   -    MD0080PA00X+020195Y+002905X0180Y0180     S3      
327SG               GF1   -B7         A01X+020335Y+001378X0280Y1650     S1      
317SG               VIA   -    MD0080PA00X+019154Y+002890X0180Y0180     S3      
327SG               GF1   -A4         A10X+019154Y+001378X0280Y1650     S2      
327SG               GF1   -B4         A01X+019154Y+001378X0280Y1650     S1      
317SG               VIA   -    MD0080PA00X+017820Y+005060X0180Y0180R043 S3      
317SG               VIA   -    MD0080PA00X+018034Y+004722X0180Y0180R022 S3      
317SG               VIA   -    MD0080PA00X+016354Y+005216X0180Y0180R125 S3      
317SG               VIA   -    MD0080PA00X+036510Y+018516X0180Y0180     S3      
317SG               VIA   -    MD0080PA00X+034530Y+018670X0180Y0180     S3      
317SG               VIA   -    MD0100PA00X+034730Y+017900X0200Y0200     S3      
327SG               C67   -2          A10X+035050Y+017890X0280Y0240R090 S2      
317SG               VIA   -    MD0080PA00X+031951Y+019030X0180Y0180     S3      
317SG               VIA   -    MD0080PA00X+032911Y+019030X0180Y0180     S3      
327SG               GF1   -A28        A10X+029390Y+001378X0280Y1650     S2      
317SG               VIA   -    MD0080PA00X+029580Y+002890X0180Y0180     S3      
327SG               GF1   -B29        A01X+029783Y+001378X0280Y1650     S1      
327SG               GF1   -A27        A10X+028996Y+001378X0280Y1650     S2      
317SG               VIA   -    MD0080PA00X+028806Y+002890X0180Y0180     S3      
327SG               GF1   -B26        A01X+028602Y+001378X0280Y1650     S1      
317SG               VIA   -    MD0080PA00X+029584Y+003210X0180Y0180     S3      
327SG               GF1   -B25        A01X+028209Y+001378X0280Y1650     S1      
317SG               VIA   -    MD0080PA00X+028005Y+002890X0180Y0180     S3      
327SG               GF1   -A24        A10X+027815Y+001378X0280Y1650     S2      
317SG               VIA   -    MD0080PA00X+028009Y+003210X0180Y0180     S3      
317SG               VIA   -    MD0080PA00X+026351Y+007630X0180Y0180     S3      
317SG               VIA   -    MD0080PA00X+027866Y+007630X0180Y0180     S3      
317SG               VIA   -    MD0080PA00X+027311Y+007630X0180Y0180     S3      
317SG               VIA   -    MD0100PA00X+027233Y+005487X0200Y0200     S3      
327SG               U3    -3          A01X+027540Y+005794X0130Y0380R090 S1      
317SG               VIA   -    MD0080PA00X+026434Y+004170X0180Y0180     S3      
327SG               GF1   -B22        A01X+027028Y+001378X0280Y1650     S1      
317SG               VIA   -    MD0080PA00X+027231Y+002890X0180Y0180     S3      
327SG               GF1   -A23        A10X+027421Y+001378X0280Y1650     S2      
327SG               GF1   -B21        A01X+026634Y+001378X0280Y1650     S1      
317SG               VIA   -    MD0080PA00X+026430Y+002890X0180Y0180     S3      
327SG               GF1   -A20        A10X+026240Y+001378X0280Y1650     S2      
317SG               VIA   -    MD0080PA00X+026434Y+003210X0180Y0180     S3      
317SG               VIA   -    MD0080PA00X+025342Y+007630X0180Y0180     S3      
317SG               VIA   -    MD0100PA00X+025950Y+007010X0200Y0200     S3      
327SG               R55   -2          A01X+025950Y+006550X0280Y0240R180 S1      
327SG               GF1   -A15        A10X+024272Y+001378X0280Y1650     S2      
317SG               VIA   -    MD0080PA00X+024462Y+002890X0180Y0180     S3      
327SG               GF1   -B16        A01X+024665Y+001378X0280Y1650     S1      
317SG               VIA   -    MD0080PA00X+025453Y+002890X0180Y0180     S3      
327SG               GF1   -A18        A10X+025453Y+001378X0280Y1650     S2      
327SG               GF1   -B18        A01X+025453Y+001378X0280Y1650     S1      
317SG               VIA   -    MD0080PA00X+024382Y+007630X0180Y0180     S3      
317SG               VIA   -    MD0080PA00X+024051Y+006670X0180Y0180     S3      
317SG               VIA   -    MD0080PA00X+024051Y+007630X0180Y0180     S3      
317SG               VIA   -    MD0080PA00X+023270Y+002910X0180Y0180     S3      
327SG               GF1   -B13        A01X+023484Y+001378X0280Y1650     S1      
327SG               GF1   -A12        A10X+023090Y+001378X0280Y1650     S2      
317SG               VIA   -    MD0100PA00X+035600Y+013050X0200Y0200     S3      
317SG               VIA   -    MD0100PA00X+035350Y+013050X0200Y0200     S3      
317SG               VIA   -    MD0100PA00X+035100Y+013050X0200Y0200     S3      
317SG               VIA   -    MD0100PA00X+035400Y+012800X0200Y0200     S3      
317SG               VIA   -    MD0080PA00X+035786Y+010471X0180Y0180     S3      
317SG               VIA   -    MD0080PA00X+035930Y+009200X0180Y0180     S3      
317SG               VIA   -    MD0080PA00X+036540Y+005420X0180Y0180     S3      
317SG               VIA   -    MD0080PA00X+036140Y+005420X0180Y0180     S3      
317SG               VIA   -    MD0080PA00X+035740Y+005420X0180Y0180     S3      
317SG               VIA   -    MD0080PA00X+035340Y+005420X0180Y0180     S3      
317SG               VIA   -    MD0080PA00X+034940Y+005420X0180Y0180     S3      
317SG               VIA   -    MD0080PA00X+033750Y+012260X0180Y0180     S3      
317SG               VIA   -    MD0080PA00X+033750Y+011300X0180Y0180     S3      
317SG               VIA   -    MD0080PA00X+034826Y+010471X0180Y0180     S3      
317SG               VIA   -    MD0080PA00X+034820Y+010850X0180Y0180     S3      
317SG               VIA   -    MD0080PA00X+033860Y+010850X0180Y0180     S3      
317SG               VIA   -    MD0080PA00X+033340Y+005420X0180Y0180     S3      
317SG               VIA   -    MD0080PA00X+034540Y+005420X0180Y0180     S3      
317SG               VIA   -    MD0080PA00X+034140Y+005420X0180Y0180     S3      
317SG               VIA   -    MD0080PA00X+033740Y+005420X0180Y0180     S3      
317SG               VIA   -    MD0080PA00X+031702Y+008298X0180Y0180     S3      
317SG               VIA   -    MD0080PA00X+031740Y+005420X0180Y0180     S3      
317SG               VIA   -    MD0080PA00X+032140Y+005420X0180Y0180     S3      
317SG               VIA   -    MD0080PA00X+032540Y+005420X0180Y0180     S3      
317SG               VIA   -    MD0080PA00X+032940Y+005420X0180Y0180     S3      
317SG               VIA   -    MD0080PA00X+031024Y+008976X0180Y0180     S3      
317SG               VIA   -    MD0100PA00X+030350Y+006940X0200Y0200     S3      
327SG               C37   -2          A01X+029972Y+006678X0280Y0240     S1      
317SG               VIA   -    MD0080PA00X+029873Y+004947X0180Y0180     S3      
317SG               VIA   -    MD0080PA00X+029873Y+004353X0180Y0180     S3      
317SG               VIA   -    MD0080PA00X+030771Y+002890X0180Y0180     S3      
327SG               GF1   -A31        A10X+030571Y+001378X0280Y1650     S2      
317SG               VIA   -    MD0080PA00X+028826Y+007630X0180Y0180     S3      
317SG               VIA   -    MD0080PA00X+029584Y+004170X0180Y0180     S3      
317SG               VIA   -    MD0080PA00X+028009Y+004170X0180Y0180     S3      
317SG               VIA   -    MD0080PA00X+039845Y+011610X0180Y0180     S3      
317SG               VIA   -    MD0080PA00X+039000Y+010050X0180Y0180R090 S3      
317SG               VIA   -    MD0080PA00X+039640Y+010050X0180Y0180R090 S3      
317SG               VIA   -    MD0080PA00X+039740Y+005420X0180Y0180     S3      
317SG               VIA   -    MD0080PA00X+039340Y+005420X0180Y0180     S3      
317SG               VIA   -    MD0080PA00X+038940Y+005420X0180Y0180     S3      
317SG               VIA   -    MD0080PA00X+038540Y+005420X0180Y0180     S3      
317SG               VIA   -    MD0100PA00X+037980Y+017710X0200Y0200     S3      
317SG               VIA   -    MD0100PA00X+036470Y+016940X0200Y0200     S3      
317SG               VIA   -    MD0100PA00X+036760Y+016930X0200Y0200     S3      
317SG               VIA   -    MD0100PA00X+037180Y+013200X0200Y0200     S3      
317SG               VIA   -    MD0100PA00X+037430Y+013200X0200Y0200     S3      
317SG               VIA   -    MD0100PA00X+037180Y+012900X0200Y0200     S3      
317SG               VIA   -    MD0100PA00X+037430Y+012900X0200Y0200     S3      
317SG               VIA   -    MD0100PA00X+036700Y+012600X0200Y0200     S3      
317SG               VIA   -    MD0100PA00X+038400Y+010950X0200Y0200     S3      
327SG               C291  -2   M      A01X+037980Y+010600X0380Y0540     S1      
317SG               VIA   -    MD0100PA00X+038400Y+010298X0200Y0200     S3      
327SG               C164  -2   M      A10X+037980Y+010600X0380Y0540R180 S2      
317SG               VIA   -    MD0100PA00X+037684Y+010023X0200Y0200     S3      
317SG               VIA   -    MD0080PA00X+037350Y+009400X0180Y0180R090 S3      
317SG               VIA   -    MD0080PA00X+036890Y+009200X0180Y0180     S3      
317SG               VIA   -    MD0080PA00X+038050Y+007740X0180Y0180R090 S3      
327SG               C245  -2          A10X+037700Y+007690X0280Y0240R090 S2      
317SG               VIA   -    MD0080PA00X+037350Y+007800X0180Y0180R090 S3      
317SG               VIA   -    MD0080PA00X+037950Y+007250X0180Y0180R090 S3      
327SG               R242  -2          A01X+041010Y+009700X0280Y0240     S1      
327SG               Y4    -3          A01X+040800Y+007522X0390Y0550R090 S1      
327SG               C247  -2          A01X+037690Y+009700X0280Y0240R180 S1      
327SG               R240  -2   M      A01X+039640Y+009700X0280Y0240R180 S1      
327SG               C249  -2          A01X+039110Y+009700X0280Y0240     S1      
317SG               VIA   -    MD0080PA00X+038140Y+005420X0180Y0180     S3      
317SG               VIA   -    MD0080PA00X+037740Y+005420X0180Y0180     S3      
317SG               VIA   -    MD0080PA00X+037340Y+005420X0180Y0180     S3      
317SG               VIA   -    MD0080PA00X+036940Y+005420X0180Y0180     S3      
317SG               VIA   -    MD0100PA00X+035510Y+016940X0200Y0200     S3      
317SG               VIA   -    MD0100PA00X+035760Y+016940X0200Y0200     S3      
317SG               VIA   -    MD0100PA00X+035260Y+016940X0200Y0200     S3      
317SG               VIA   -    MD0100PA00X+035010Y+016940X0200Y0200     S3      
317SG               VIA   -    MD0100PA00X+036360Y+017660X0200Y0200     S3      
327SG               R104  -2          A01X+036040Y+017455X0280Y0240R270 S1      
327SG               C124  -2          A10X+040097Y+014497X0250Y0250R090 S2      
327SG               C213  -2          A10X+040491Y+014104X0250Y0250R270 S2      
327SG               C106  -2          A10X+040097Y+018041X0250Y0250     S2      
327SG               C222  -2          A10X+041278Y+016466X0250Y0250R090 S2      
327SG               C118  -2          A10X+041278Y+015678X0250Y0250R180 S2      
327SG               C131  -2          A10X+040097Y+016072X0250Y0250R090 S2      
327SG               C105  -2          A10X+040491Y+016466X0250Y0250R270 S2      
327SG               C218  -2          A10X+040097Y+015678X0250Y0250R270 S2      
327SG               C111  -2          A10X+041278Y+016072X0250Y0250R180 S2      
327SG               C203  -2          A10X+039704Y+018434X0250Y0250R180 S2      
327SG               GF1   -B32        A01X+030964Y+001378X0280Y1650     S1      
327SG               C205  -2          A10X+039310Y+017647X0250Y0250R270 S2      
327SG               C104  -2          A10X+038443Y+017450X0280Y0240     S2      
327SG               C209  -2          A10X+039704Y+016466X0250Y0250R180 S2      
327SG               C117  -2          A10X+039704Y+015285X0250Y0250R180 S2      
327SG               C217  -2          A10X+039704Y+014891X0250Y0250R270 S2      
327SG               C110  -2          A10X+038916Y+014891X0250Y0250     S2      
327SG               C116  -2          A10X+038763Y+012936X0280Y0240     S2      
317SG               MAC_PI-1   MD0790PA00X+028607Y+010404X1000Y1000     S3      
317SG               VIA   -    MD0080PA00X+046053Y+012217X0180Y0180     S3      
317SG               VIA   -    MD0080PA00X+010410Y+038250X0180Y0180     S3      
317SG               VIA   -    MD0080PA00X+011370Y+038250X0180Y0180     S3      
317SG               VIA   -    MD0080PA00X+065604Y+014120X0180Y0180R090 S3      
317SG               VIA   -    MD0080PA00X+065604Y+013720X0180Y0180R090 S3      
317SG               VIA   -    MD0080PA00X+065604Y+013320X0180Y0180R090 S3      
317SG               VIA   -    MD0080PA00X+065604Y+012920X0180Y0180R090 S3      
317SG               VIA   -    MD0080PA00X+065604Y+012520X0180Y0180R090 S3      
317SG               VIA   -    MD0080PA00X+065604Y+012120X0180Y0180R090 S3      
317SG               VIA   -    MD0080PA00X+065604Y+011720X0180Y0180R090 S3      
317SG               VIA   -    MD0080PA00X+065604Y+011320X0180Y0180R090 S3      
317SG               VIA   -    MD0080PA00X+065604Y+010920X0180Y0180R090 S3      
327SG               U27   -9   M      A01X+059900Y+020940X0390Y0710R090 S0      
317SG               VIA   -    MD0100PA00X+059645Y+021035X0200Y0200     S3      
317SG               VIA   -    MD0100PA00X+060155Y+020845X0200Y0200     S3      
317SG               ME10  -8   MD0120PA00X+002270Y+004364X0240Y0240     S3      
317SG               ME10  -7   MD0120PA00X+001988Y+003681X0240Y0240     S3      
317SG               ME10  -6   MD0120PA00X+002270Y+002999X0240Y0240     S3      
317SG               ME10  -5   MD0120PA00X+002953Y+002716X0240Y0240     S3      
317SG               ME10  -4   MD0120PA00X+003635Y+002999X0240Y0240     S3      
317SG               ME10  -3   MD0120PA00X+003918Y+003681X0240Y0240     S3      
317SG               ME10  -2   MD0120PA00X+003635Y+004364X0240Y0240     S3      
317SG               ME10  -1   MD0120PA00X+002953Y+004646X0240Y0240     S3      
317SG               ME12  -8   MD0120PA00X+063322Y+007218X0240Y0240     S3      
317SG               ME12  -7   MD0120PA00X+063039Y+006535X0240Y0240     S3      
317SG               ME12  -6   MD0120PA00X+063322Y+005853X0240Y0240     S3      
317SG               ME12  -5   MD0120PA00X+064004Y+005570X0240Y0240     S3      
317SG               ME12  -4   MD0120PA00X+064686Y+005853X0240Y0240     S3      
317SG               ME12  -3   MD0120PA00X+064969Y+006535X0240Y0240     S3      
317SG               ME12  -2   MD0120PA00X+064686Y+007218X0240Y0240     S3      
317SG               ME12  -1   MD0120PA00X+064004Y+007500X0240Y0240     S3      
317SG               ME11  -8   MD0120PA00X+063322Y+042466X0240Y0240     S3      
317SG               ME11  -7   MD0120PA00X+063039Y+041784X0240Y0240     S3      
317SG               ME11  -6   MD0120PA00X+063322Y+041101X0240Y0240     S3      
317SG               ME11  -5   MD0120PA00X+064004Y+040818X0240Y0240     S3      
317SG               ME11  -4   MD0120PA00X+064686Y+041101X0240Y0240     S3      
317SG               ME11  -3   MD0120PA00X+064969Y+041784X0240Y0240     S3      
317SG               ME11  -2   MD0120PA00X+064686Y+042466X0240Y0240     S3      
317SG               ME11  -1   MD0120PA00X+064004Y+042748X0240Y0240     S3      
327SG               J5    -10         A01X+059945Y+013706X0560Y0880R090 S1      
317SG               VIA   -    MD0100PA00X+059200Y+013600X0200Y0200     S3      
317SG               VIA   -    MD0100PA00X+062200Y+013600X0200Y0200     S3      
327SG               J5    -9          A01X+061465Y+013706X0560Y0920R090 S1      
317SG               VIA   -    MD0100PA00X+059900Y+009250X0200Y0200     S3      
327SG               U36   -4          A01X+060845Y+010066X0180Y0600R090 S1      
327SG               C316  -2          A10X+042400Y+039830X0280Y0240R270 S2      
327SG               C101  -2          A10X+012650Y+036060X0280Y0240R270 S2      
317SG               VIA   -    MD0100PA00X+058030Y+038570X0200Y0200R270 S3      
327SG               C301  -2          A10X+054650Y+034410X0380Y0540     S2      
327SG               C299  -2          A10X+054650Y+032880X0380Y0540     S2      
327SG               C297  -2          A10X+054650Y+033640X0380Y0540     S2      
327SG               C303  -2          A10X+054610Y+032060X0380Y0540     S2      
317SG               VIA   -    MD0100PA00X+013550Y+039050X0200Y0200     S3      
327SG               Y2    -4          A01X+012983Y+038515X0550Y0470R180 S1      
317SG               VIA   -    MD0100PA00X+012117Y+039689X0200Y0200     S3      
327SG               Y2    -2          A01X+012117Y+039185X0550Y0470R180 S1      
317SG               VIA   -    MD0100PA00X+004200Y+023680X0200Y0200     S3      
327SG               R498  -1          A01X+004520Y+023680X0280Y0240R270 S1      
327SG               R488  -2          A10X+018850Y+029810X0280Y0240R270 S2      
317SG               VIA   -    MD0100PA00X+053250Y+027250X0200Y0200     S3      
327SG               C193  -2          A01X+052904Y+027250X0120Y0150     S1      
327SG               U27   -8          A01X+059605Y+021438X0410Y0120R090 S1      
327SG               U27   -7          A01X+059802Y+021438X0410Y0120R090 S1      
317SG               VIA   -    MD0100PA00X+016985Y+029895X0200Y0200     S3      
317SG               VIA   -    MD0100PA00X+016615Y+030405X0200Y0200     S3      
327SG               U41   -5          A01X+016203Y+029756X0410Y0210     S1      
327SG               U41   -11  M      A01X+016800Y+030150X0570Y0710     S0      
317SG               VIA   -    MD0100PA00X+056435Y+006535X0200Y0200     S3      
317SG               VIA   -    MD0100PA00X+051265Y+026815X0200Y0200R180 S3      
317SG               VIA   -    MD0100PA00X+050895Y+027325X0200Y0200R180 S3      
327SG               U21   -5          A01X+051677Y+027464X0410Y0210R180 S1      
327SG               U21   -11  M      A01X+051080Y+027070X0570Y0710R180 S0      
327SG               U1    -7          A01X+055927Y+037764X0470Y0120R180 S1      
327SG               U33   -18         A01X+040489Y+039920X0490Y0120R180 S1      
327SG               U33   -25         A01X+041440Y+038969X0120Y0490R180 S1      
327SG               U33   -11         A01X+041440Y+040871X0120Y0490R180 S1      
317SG               VIA   -    MD0100PA00X+041915Y+040395X0200Y0200R180 S3      
317SG               VIA   -    MD0100PA00X+040965Y+039445X0200Y0200R180 S3      
317SG               VIA   -    MD0100PA00X+041235Y+039715X0200Y0200R180 S3      
317SG               VIA   -    MD0100PA00X+041645Y+039715X0200Y0200R180 S3      
317SG               VIA   -    MD0100PA00X+041645Y+040125X0200Y0200R180 S3      
317SG               VIA   -    MD0100PA00X+041235Y+040125X0200Y0200R180 S3      
317SG               VIA   -    MD0100PA00X+040965Y+040395X0200Y0200R180 S3      
317SG               VIA   -    MD0100PA00X+041915Y+039445X0200Y0200R180 S3      
327SG               U33   -29  M      A01X+041440Y+039920X1150Y1150R180 S0      
327SG               U22   -4          A01X+044198Y+028858X0330Y0120R180 S1      
317SG               VIA   -    MD0100PA00X+045000Y+040700X0200Y0200     S3      
317SG               VIA   -    MD0100PA00X+043100Y+041600X0200Y0200     S3      
317SG               VIA   -    MD0100PA00X+014100Y+029850X0200Y0200     S3      
327SG               R491  -2          A10X+014790Y+030000X0280Y0240     S2      
327SG               R489  -2          A01X+014840Y+029500X0280Y0240R180 S1      
327SG               C308  -2          A01X+014600Y+030070X0380Y0540R270 S1      
317SG               VIA   -    MD0100PA00X+014500Y+029650X0200Y0200     S3      
327SG               U35   -4          A01X+020966Y+032655X0180Y0600     S1      
327SG               C309  -2          A01X+015100Y+032060X0280Y0240R090 S1      
317SG               VIA   -    MD0100PA00X+015100Y+032420X0200Y0200     S3      
327SG               C284  -2          A01X+018480Y+032600X0380Y0540     S1      
327SG               C300  -2          A01X+018880Y+031050X0380Y0540     S1      
327SG               C298  -2          A01X+018610Y+031900X0280Y0240     S1      
327SG               C302  -2          A01X+018850Y+029810X0280Y0240R090 S1      
327SG               C304  -2          A01X+018660Y+030400X0280Y0240     S1      
317SG               VIA   -    MD0100PA00X+018900Y+032600X0200Y0200     S3      
317SG               VIA   -    MD0100PA00X+018950Y+031900X0200Y0200     S3      
317SG               VIA   -    MD0100PA00X+019000Y+030550X0200Y0200     S3      
317SG               VIA   -    MD0100PA00X+019000Y+030150X0200Y0200     S3      
317SG               VIA   -    MD0100PA00X+016500Y+029400X0200Y0200     S3      
317SG               VIA   -    MD0100PA00X+016850Y+029400X0200Y0200     S3      
327SG               C307  -2          A01X+017146Y+029000X0120Y0150R180 S1      
327SG               R503  -2          A10X+047184Y+020796X0250Y0250R180 S2      
327SG               R504  -2          A10X+047184Y+021584X0250Y0250R270 S2      
327SG               R501  -1          A10X+046810Y+017550X0280Y0240     S2      
317SG               VIA   -    MD0100PA00X+051700Y+021250X0200Y0200     S3      
327SG               R500  -1          A10X+047184Y+016860X0250Y0250     S2      
327SG               R271  -1          A10X+046790Y+018434X0250Y0250R270 S2      
327SG               R270  -1          A10X+045609Y+018828X0250Y0250R180 S2      
317SG               VIA   -    MD0100PA00X+049600Y+017926X0200Y0200     S3      
317SG               VIA   -    MD0100PA00X+045900Y+032600X0200Y0200     S3      
327SG               C97   -2   M      A01X+045510Y+032700X0280Y0240     S1      
317SG               VIA   -    MD0080PA00X+028660Y+019870X0180Y0180     S3      
317SG               VIA   -    MD0080PA00X+027700Y+019870X0180Y0180     S3      
327SG               R359  -2          A01X+044585Y+011230X0280Y0240     S1      
327SG               R360  -2          A01X+043245Y+011230X0280Y0240R180 S1      
317SG               VIA   -    MD0080PA00X+045093Y+012217X0180Y0180     S3      
317SG               VIA   -    MD0080PA00X+000400Y+028562X0180Y0180R270 S3      
317SG               VIA   -    MD0080PA00X+000400Y+028162X0180Y0180R270 S3      
317SG               VIA   -    MD0080PA00X+000400Y+031362X0180Y0180R270 S3      
317SG               VIA   -    MD0080PA00X+000400Y+030962X0180Y0180R270 S3      
317SG               VIA   -    MD0080PA00X+000400Y+030562X0180Y0180R270 S3      
317SG               VIA   -    MD0080PA00X+000400Y+030162X0180Y0180R270 S3      
317SG               VIA   -    MD0100PA00X+034900Y+030300X0200Y0200R270 S3      
317SG               VIA   -    MD0100PA00X+035550Y+030650X0200Y0200R270 S3      
317SG               VIA   -    MD0100PA00X+036950Y+026750X0200Y0200     S3      
327SG               U34   -2          A01X+036950Y+026265X0200Y0470     S1      
317SG               VIA   -    MD0100PA00X+037250Y+023200X0200Y0200     S3      
327SG               C250  -2          A01X+037050Y+023840X0280Y0240R270 S1      
317SG               VIA   -    MD0100PA00X+009450Y+010500X0200Y0200R090 S3      
317SG               VIA   -    MD0100PA00X+046350Y+008650X0200Y0200     S3      
327SG               R483  -1          A10X+046940Y+009150X0280Y0240R180 S2      
317SG               VIA   -    MD0100PA00X+008660Y+014130X0200Y0200     S3      
317SG               VIA   -    MD0100PA00X+028850Y+031700X0200Y0200     S3      
327SG               C38   -2          A01X+028950Y+032060X0280Y0240R180 S1      
317SG               VIA   -    MD0100PA00X+008300Y+041700X0200Y0200     S3      
317SG               VIA   -    MD0100PA00X+004550Y+012600X0200Y0200     S3      
327SG               R496  -1          A01X+004550Y+012200X0280Y0240R270 S1      
317SG               VIA   -    MD0100PA00X+001750Y+009100X0200Y0200     S3      
327SG               CR5   -1          A01X+002055Y+009565X0570Y0430R090 S1      
317SG               VIA   -    MD0100PA00X+001700Y+020450X0200Y0200     S3      
327SG               CR4   -1          A01X+002055Y+020965X0570Y0430R090 S1      
317SG               VIA   -    MD0100PA00X+004550Y+016100X0200Y0200     S3      
327SG               R499  -1          A01X+004550Y+016440X0280Y0240R090 S1      
317SG               VIA   -    MD0100PA00X+013200Y+037550X0200Y0200     S3      
317SG               VIA   -    MD0100PA00X+012510Y+030610X0200Y0200     S3      
327SG               U18   -47         A01X+012510Y+031200X0120Y0640     S1      
317SG               VIA   -    MD0100PA00X+009559Y+033335X0200Y0200     S3      
327SG               U18   -25         A01X+008940Y+033392X0120Y0640R090 S1      
317SG               VIA   -    MD0100PA00X+005750Y+028900X0200Y0200     S3      
327SG               U8    -4          A10X+005505Y+029516X0180Y0600R270 S2      
317SG               VIA   -    MD0100PA00X+001600Y+030250X0200Y0200     S3      
327SG               R338  -2          A10X+001990Y+030250X0280Y0240     S2      
317SG               VIA   -    MD0100PA00X+001600Y+030750X0200Y0200     S3      
327SG               C39   -1          A10X+001990Y+030750X0280Y0240R180 S2      
327SG               C74   -2          A01X+014450Y+037040X0280Y0240R270 S1      
327SG               R445  -2          A01X+006310Y+032900X0280Y0240     S1      
327SG               C94   -2          A10X+007000Y+033840X0280Y0240R090 S2      
317SG               VIA   -    MD0100PA00X+007200Y+033500X0200Y0200     S3      
327SG               U17   -2          A01X+007200Y+033935X0200Y0470R180 S1      
317SG               VIA   -    MD0100PA00X+006350Y+035960X0200Y0200     S3      
327SG               R442  -2          A01X+005950Y+035960X0280Y0240R090 S1      
317SG               VIA   -    MD0080PA00X+006710Y+035750X0180Y0180     S3      
317SG               VIA   -    MD0080PA00X+007670Y+035750X0180Y0180     S3      
317SG               VIA   -    MD0100PA00X+014213Y+032563X0200Y0200     S3      
327SG               U18   -51         A01X+013520Y+032407X0120Y0640R090 S1      
327SG               R453  -2   M      A01X+044260Y+037450X0280Y0240     S1      
317SG               VIA   -    MD0100PA00X+044720Y+034750X0200Y0200     S3      
327SG               Q1    -2          A01X+044720Y+035315X0390Y0550     S1      
327SG               R114  -2          A01X+047350Y+035040X0280Y0240R270 S1      
317SG               VIA   -    MD0100PA00X+059770Y+018700X0200Y0200     S3      
317SG               VIA   -    MD0100PA00X+006060Y+016120X0200Y0200     S3      
327SG               C84   -2          A01X+006060Y+016474X0280Y0240R270 S1      
317SG               VIA   -    MD0100PA00X+053300Y+008700X0200Y0200     S3      
327SG               R484  -1   M      A01X+052910Y+008700X0280Y0240R180 S1      
327SG               C92   -2          A01X+052910Y+009200X0280Y0240     S1      
317SG               VIA   -    MD0100PA00X+062699Y+023799X0200Y0200     S3      
327SG               U9    -2          A01X+062699Y+023148X0200Y0470     S1      
317SG               VIA   -    MD0100PA00X+044600Y+037450X0200Y0200     S3      
327SG               C89   -2          A01X+044260Y+037900X0280Y0240     S1      
327SG               U23   -4          A01X+037690Y+033850X0720Y0200R180 S1      
317SG               VIA   -    MD0100PA00X+038300Y+034150X0200Y0200     S3      
327SG               R192  -2          A10X+035060Y+033250X0280Y0240R180 S2      
317SG               VIA   -    MD0080PA00X+035500Y+033250X0180Y0180R180 S3      
317SG               VIA   -    MD0100PA00X+063350Y+030150X0200Y0200     S3      
327SG               J10   -9          A01X+062236Y+030150X0500Y1400R090 S1      
317SG               VIA   -    MD0100PA00X+016670Y+033880X0200Y0200     S3      
327SG               R130  -2          A10X+009950Y+035640X0280Y0240R090 S2      
327SG               C310  -1          A01X+005104Y+015700X0120Y0150R180 S1      
327SG               R437  -1          A10X+044822Y+018040X0250Y0250R270 S2      
327SG               R436  -1          A10X+044428Y+018040X0250Y0250R270 S2      
327SG               C206  -2          A10X+044034Y+018041X0250Y0250R180 S2      
327SG               C126  -2          A10X+044822Y+019615X0250Y0250R270 S2      
327SG               C244  -2          A10X+043110Y+007300X0280Y0240R180 S2      
317SG               VIA   -    MD0100PA00X+015910Y+035040X0200Y0200     S3      
327SG               C88   -2          A10X+016300Y+035040X0280Y0240R090 S2      
327SG               C90   -2          A10X+010350Y+030940X0280Y0240R090 S2      
317SG               VIA   -    MD0100PA00X+010450Y+030550X0200Y0200     S3      
327SG               U18   -35         A01X+010147Y+031200X0120Y0640     S1      
317SG               VIA   -    MD0100PA00X+014200Y+035000X0200Y0200     S3      
327SG               C96   -2          A10X+013760Y+035000X0280Y0240R180 S2      
317SG               VIA   -    MD0100PA00X+012350Y+034750X0200Y0200     S3      
327SG               C95   -2          A10X+011960Y+034750X0280Y0240R180 S2      
327SG               C98   -2          A10X+010850Y+036060X0280Y0240R270 S2      
327SG               C91   -2          A10X+013750Y+035590X0280Y0240R090 S2      
317SG               VIA   -    MD0100PA00X+012000Y+037150X0200Y0200     S3      
327SG               R463  -2          A10X+011750Y+036060X0280Y0240R270 S2      
327SG               C99   -2          A10X+012200Y+036060X0280Y0240R270 S2      
327SG               C100  -2          A10X+011300Y+036060X0280Y0240R270 S2      
317SG               VIA   -    MD0100PA00X+014090Y+035540X0200Y0200     S3      
317SG               VIA   -    MD0100PA00X+012000Y+036800X0200Y0200     S3      
317SG               VIA   -    MD0100PA00X+011550Y+038900X0200Y0200     S3      
317SG               VIA   -    MD0100PA00X+011700Y+039700X0200Y0200     S3      
317SG               VIA   -    MD0100PA00X+012700Y+039706X0200Y0200     S3      
317SG               VIA   -    MD0100PA00X+012900Y+037050X0200Y0200     S3      
317SG               VIA   -    MD0100PA00X+013550Y+038300X0200Y0200     S3      
317SG               VIA   -    MD0100PA00X+013550Y+039600X0200Y0200     S3      
317SG               VIA   -    MD0100PA00X+011850Y+037900X0200Y0200     S3      
327SG               C87   -1          A01X+012146Y+037900X0120Y0150     S1      
317SG               VIA   -    MD0100PA00X+013200Y+037900X0200Y0200     S3      
327SG               C86   -1          A01X+012904Y+037900X0120Y0150R180 S1      
317SG               VIA   -    MD0100PA00X+012900Y+036500X0200Y0200     S3      
327SG               U18   -1          A01X+012706Y+035780X0120Y0640     S1      
317SG               VIA   -    MD0100PA00X+058030Y+035670X0200Y0200     S3      
317SG               VIA   -    MD0100PA00X+054300Y+039670X0200Y0200     S3      
317SG               VIA   -    MD0100PA00X+061650Y+019487X0200Y0200     S3      
327SG               R103  -2          A10X+062100Y+019677X0280Y0240R090 S2      
327SG               J11   -5          A01X+064105Y+021614X0160Y0530R090 S1      
317SG               VIA   -    MD0100PA00X+010380Y+007624X0200Y0200     S3      
317SG               VIA   -    MD0100PA00X+040370Y+025930X0200Y0200     S3      
317SG               VIA   -    MD0100PA00X+039780Y+025930X0200Y0200     S3      
327SG               R326  -1          A10X+042090Y+025520X0280Y0240R090 S2      
327SG               R328  -1   M      A10X+041500Y+025520X0280Y0240R090 S2      
327SG               R309  -1   M      A10X+040930Y+025520X0280Y0240R090 S2      
327SG               R293  -1   M      A10X+040370Y+025520X0280Y0240R090 S2      
327SG               R171  -1   M      A10X+039780Y+025520X0280Y0240R090 S2      
327SG               R173  -1   M      A10X+039190Y+025520X0280Y0240R090 S2      
327SG               R286  -1          A10X+038010Y+025520X0280Y0240R090 S2      
327SG               R284  -1   M      A10X+038600Y+025520X0280Y0240R090 S2      
317SG               VIA   -    MD0100PA00X+048100Y+007070X0200Y0200     S3      
327SG               U37   -8          A01X+048855Y+007404X0140Y0620R090 S1      
327SG               C176  -2          A01X+052975Y+013450X0450Y1040     S1      
327SG               C173  -2          A01X+052730Y+012400X0380Y0540     S1      
317SG               VIA   -    MD0100PA00X+064700Y+011350X0200Y0200     S3      
327SG               C305  -1          A01X+064210Y+011350X0280Y0240R180 S1      
317SG               VIA   -    MD0100PA00X+045950Y+032200X0200Y0200     S3      
327SG               R459  -1   M      A01X+045540Y+032200X0280Y0240R180 S1      
327SG               C102  -2          A10X+041700Y+034710X0280Y0240R270 S2      
317SG               VIA   -    MD0100PA00X+041750Y+035200X0200Y0200     S3      
327SG               U40   -2          A01X+041750Y+034824X0240Y0170R270 S1      
327SG               C123  -2          A10X+039800Y+034710X0280Y0240R270 S2      
317SG               VIA   -    MD0100PA00X+039800Y+035200X0200Y0200     S3      
327SG               U39   -2          A01X+039800Y+034804X0240Y0170R270 S1      
317SG               VIA   -    MD0100PA00X+039730Y+032070X0200Y0200     S3      
327SG               R458  -1          A10X+039730Y+032390X0280Y0240R180 S2      
317SG               VIA   -    MD0100PA00X+040750Y+030500X0200Y0200     S3      
327SG               U38   -8          A01X+041695Y+030664X0140Y0620R090 S1      
317SG               VIA   -    MD0100PA00X+038390Y+037260X0200Y0200     S3      
327SG               R451  -2          A10X+038390Y+037580X0280Y0240     S2      
327SG               U30   -8          A01X+040355Y+035854X0140Y0620R090 S1      
317SG               VIA   -    MD0100PA00X+041000Y+035854X0200Y0200     S3      
327SG               C2    -2          A01X+056370Y+035690X0280Y0240     S1      
317SG               VIA   -    MD0100PA00X+056370Y+035240X0200Y0200R270 S3      
327SG               CR3   -A          A10X+053160Y+035200X0850Y1080R270 S2      
317SG               VIA   -    MD0100PA00X+052760Y+031890X0200Y0200R090 S3      
317SG               VIA   -    MD0100PA00X+053290Y+031890X0200Y0200R090 S3      
317SG               VIA   -    MD0100PA00X+053860Y+031890X0200Y0200R090 S3      
317SG               VIA   -    MD0100PA00X+052710Y+034560X0200Y0200R090 S3      
317SG               VIA   -    MD0100PA00X+052710Y+034060X0200Y0200R090 S3      
317SG               VIA   -    MD0100PA00X+053240Y+034560X0200Y0200R090 S3      
317SG               VIA   -    MD0100PA00X+053810Y+034560X0200Y0200R090 S3      
317SG               VIA   -    MD0100PA00X+053240Y+034060X0200Y0200R090 S3      
317SG               VIA   -    MD0100PA00X+053810Y+034060X0200Y0200R090 S3      
327SG               CR10  -A          A01X+052911Y+033060X0940Y1300     S1      
327SG               R7    -1          A01X+057620Y+036170X0280Y0240R180 S1      
317SG               VIA   -    MD0100PA00X+058020Y+036170X0200Y0200R270 S3      
327SG               C4    -1          A01X+057314Y+037120X0120Y0150R180 S1      
317SG               VIA   -    MD0100PA00X+057630Y+037120X0200Y0200R270 S3      
327SG               C5    -2   M      A01X+057620Y+038070X0280Y0240     S1      
327SG               R46   -1   M      A01X+057620Y+037570X0280Y0240R180 S1      
327SG               C7    -2   M      A01X+057620Y+038570X0280Y0240     S1      
317SG               VIA   -    MD0100PA00X+058030Y+037570X0200Y0200R270 S3      
317SG               VIA   -    MD0100PA00X+058030Y+038070X0200Y0200R270 S3      
327SG               R14   -2          A01X+056010Y+039150X0280Y0240     S1      
317SG               VIA   -    MD0100PA00X+056020Y+038650X0200Y0200R270 S3      
317SG               VIA   -    MD0100PA00X+056450Y+037900X0200Y0200R270 S3      
327SG               C8    -2          A01X+054856Y+039120X0120Y0150R180 S1      
317SG               VIA   -    MD0100PA00X+054856Y+038770X0200Y0200R270 S3      
317SG               VIA   -    MD0100PA00X+052370Y+037770X0200Y0200     S3      
317SG               VIA   -    MD0100PA00X+052820Y+037770X0200Y0200     S3      
317SG               VIA   -    MD0100PA00X+052370Y+038410X0200Y0200     S3      
317SG               VIA   -    MD0100PA00X+053220Y+037770X0200Y0200     S3      
327SG               C6    -2          A01X+052980Y+038270X0380Y0540R180 S1      
327SG               C10   -2          A01X+052540Y+037380X0380Y0540R090 S1      
327SG               C9    -2          A01X+053360Y+037380X0380Y0540R090 S1      
317SG               VIA   -    MD0100PA00X+053850Y+040788X0200Y0200     S3      
327SG               DS6   -C   M      A01X+054350Y+040788X0310Y0310R270 S1      
327SG               DS7   -C   M      A01X+055532Y+040788X0310Y0310R270 S1      
327SG               DS8   -C   M      A01X+056713Y+040788X0310Y0310R270 S1      
327SG               DS5   -C   M      A01X+057894Y+040788X0310Y0310R270 S1      
327SG               DS19  -C   M      A01X+059075Y+040788X0310Y0310R270 S1      
327SG               DS12  -C          A01X+061437Y+040788X0310Y0310R270 S1      
327SG               DS20  -C   M      A01X+060256Y+040788X0310Y0310R270 S1      
327SG               R336  -2          A10X+001990Y+028750X0280Y0240     S2      
317SG               VIA   -    MD0100PA00X+001990Y+028300X0200Y0200     S3      
327SG               R334  -2          A10X+002900Y+028290X0280Y0240R090 S2      
317SG               VIA   -    MD0100PA00X+012000Y+036450X0200Y0200     S3      
327SG               U18   -5          A01X+011919Y+035780X0120Y0640     S1      
317SG               VIA   -    MD0100PA00X+011000Y+036400X0200Y0200     S3      
327SG               U18   -10         A01X+010935Y+035780X0120Y0640     S1      
317SG               VIA   -    MD0100PA00X+010650Y+036400X0200Y0200     S3      
327SG               U18   -11         A01X+010738Y+035780X0120Y0640     S1      
317SG               VIA   -    MD0100PA00X+010300Y+036400X0200Y0200     S3      
317SG               VIA   -    MD0100PA00X+009900Y+035000X0200Y0200     S3      
327SG               U18   -15         A01X+009950Y+035780X0120Y0640     S1      
317SG               VIA   -    MD0100PA00X+006640Y+007740X0200Y0200     S3      
327SG               C1    -2          A10X+008600Y+008330X0280Y0240R270 S2      
317SG               VIA   -    MD0100PA00X+008330Y+008710X0200Y0200R090 S3      
327SG               R161  -2   M      A10X+008330Y+009110X0280Y0240R090 S2      
327SG               R159  -2          A10X+008780Y+009110X0280Y0240R090 S2      
317SG               VIA   -    MD0100PA00X+006600Y+009110X0200Y0200R090 S3      
327SG               R163  -2          A10X+006980Y+009110X0280Y0240R090 S2      
327SG               U19   -4          A01X+007366Y+009475X0620Y0140R270 S1      
317SG               VIA   -    MD0100PA00X+006950Y+010000X0200Y0200R090 S3      
317SG               VIA   -    MD0100PA00X+004850Y+027150X0200Y0200     S3      
327SG               C317  -1          A01X+004966Y+026800X0120Y0150     S1      
317SG               VIA   -    MD0100PA00X+005177Y+024507X0200Y0200     S3      
327SG               U15   -4          A01X+005177Y+024917X0380Y0120R270 S1      
317SG               VIA   -    MD0100PA00X+006750Y+022290X0200Y0200     S3      
327SG               C85   -2          A01X+006400Y+022290X0280Y0240R270 S1      
317SG               VIA   -    MD0100PA00X+005750Y+021850X0200Y0200     S3      
327SG               C318  -1          A01X+005164Y+021660X0120Y0150R180 S1      
317SG               VIA   -    MD0100PA00X+005177Y+018799X0200Y0200     S3      
327SG               U16   -4          A01X+005177Y+019209X0380Y0120R270 S1      
317SG               VIA   -    MD0100PA00X+005390Y+015700X0200Y0200R270 S3      
317SG               VIA   -    MD0100PA00X+005177Y+013050X0200Y0200     S3      
327SG               U13   -4          A01X+005177Y+013500X0380Y0120R270 S1      
317SG               VIA   -    MD0100PA00X+004760Y+006890X0200Y0200     S3      
327SG               R497  -1          A01X+004430Y+006890X0280Y0240R270 S1      
317SG               VIA   -    MD0100PA00X+006140Y+010490X0200Y0200     S3      
327SG               C83   -2          A01X+006250Y+010840X0280Y0240R270 S1      
317SG               VIA   -    MD0100PA00X+005177Y+007360X0200Y0200     S3      
327SG               U14   -4          A01X+005177Y+007791X0380Y0120R270 S1      
317SG               VIA   -    MD0100PA00X+004700Y+010000X0200Y0200     S3      
317SG               VIA   -    MD0100PA00X+006770Y+006500X0200Y0200     S3      
327SG               C82   -2          A10X+006770Y+006150X0280Y0240R180 S2      
317SG               VIA   -    MD0100PA00X+045460Y+010850X0200Y0200     S3      
327SG               R441  -2          A10X+045850Y+011390X0280Y0240R090 S2      
327SG               R440  -2   M      A10X+045300Y+011390X0280Y0240R090 S2      
317SG               J13   -GH1 MD0240PA00X+004370Y+035158X0350Y0750R270 S3      
317SG               J13   -GH2 MD0240PA00X+004370Y+033166X0350Y0750R270 S3      
317SG               J13   -GH3 MD0240PA00X+002481Y+034724X0350Y0750R270 S3      
317SG               J13   -GH4 MD0240PA00X+002481Y+033598X0350Y0750R270 S3      
317SG               J13   -A1  MD0160PA00X+002461Y+034315X0240Y0240R270 S3      
317SG               J13   -A12 MD0160PA00X+004587Y+034315X0240Y0240R270 S3      
317SG               J13   -B1  MD0160PA00X+004410Y+034008X0240Y0240R270 S3      
317SG               J13   -B12 MD0160PA00X+002283Y+034008X0240Y0240R270 S3      
327SG               R186  -1          A01X+038160Y+026800X0280Y0240     S1      
327SG               R237  -2          A01X+045660Y+028450X0280Y0240     S1      
327SG               R351  -2          A01X+008350Y+025240X0280Y0240R270 S1      
327SG               R346  -2          A01X+006190Y+027900X0280Y0240R180 S1      
327SG               R343  -2          A10X+008580Y+028310X0280Y0240R270 S2      
327SG               Q2    -2          A10X+030535Y+021430X0390Y0550R090 S2      
317SG               VIA   -    MD0100PA00X+057507Y+016550X0200Y0200     S3      
317SG               VIA   -    MD0100PA00X+017600Y+041600X0200Y0200     S3      
317SG               VIA   -    MD0100PA00X+022600Y+037850X0200Y0200     S3      
317SG               VIA   -    MD0100PA00X+022150Y+037850X0200Y0200     S3      
317SG               VIA   -    MD0100PA00X+038430Y+036870X0200Y0200     S3      
317SG               VIA   -    MD0100PA00X+006149Y+033233X0200Y0200     S3      
317SG               VIA   -    MD0100PA00X+053350Y+012450X0200Y0200     S3      
317SG               VIA   -    MD0100PA00X+053450Y+013000X0200Y0200     S3      
317SG               VIA   -    MD0100PA00X+053450Y+013650X0200Y0200     S3      
317SG               VIA   -    MD0100PA00X+036450Y+021300X0200Y0200     S3      
327SG               C150  -2          A10X+036510Y+021700X0280Y0240R180 S2      
317SG               VIA   -    MD0100PA00X+036700Y+021300X0200Y0200     S3      
317SG               VIA   -    MD0100PA00X+031100Y+019350X0200Y0200     S3      
317SG               VIA   -    MD0100PA00X+042940Y+010750X0200Y0200     S3      
317SG               VIA   -    MD0100PA00X+045000Y+010820X0200Y0200     S3      
327SG               C268  -2          A01X+054100Y+018360X0280Y0240R090 S1      
327SG               C270  -2          A01X+053500Y+018530X0380Y0540R090 S1      
317SG               VIA   -    MD0100PA00X+053850Y+018950X0200Y0200     S3      
317SG               VIA   -    MD0100PA00X+054250Y+018950X0200Y0200     S3      
327SG               C179  -2          A10X+054000Y+018530X0380Y0540R270 S2      
327SG               C178  -2          A10X+053900Y+016040X0280Y0240R090 S2      
317SG               VIA   -    MD0100PA00X+057646Y+016197X0200Y0200     S3      
317SG               VIA   -    MD0100PA00X+053400Y+016050X0200Y0200     S3      
317SG               VIA   -    MD0100PA00X+054400Y+015900X0200Y0200     S3      
327SG               C269  -2          A01X+057230Y+016100X0380Y0540     S1      
327SG               C271  -2          A01X+053900Y+015970X0380Y0540R270 S1      
317SG               VIA   -    MD0080PA00X+045412Y+017056X0180Y0180R180 S0      
317SG               VIA   -    MD0080PA00X+047381Y+016663X0180Y0180     S0      
317SG               VIA   -    MD0080PA00X+042656Y+021781X0180Y0180     S0      
317SG               VIA   -    MD0080PA00X+046987Y+013513X0180Y0180     S0      
317SG               VIA   -    MD0080PA00X+045784Y+013141X0180Y0180     S0      
317SG               VIA   -    MD0080PA00X+045412Y+014300X0180Y0180     S0      
317SG               VIA   -    MD0080PA00X+044231Y+015482X0180Y0180     S0      
317SG               VIA   -    MD0080PA00X+044231Y+013907X0180Y0180     S0      
317SG               VIA   -    MD0080PA00X+043837Y+015875X0180Y0180     S0      
317SG               VIA   -    MD0080PA00X+043837Y+015088X0180Y0180     S0      
317SG               VIA   -    MD0080PA00X+043837Y+016269X0180Y0180     S0      
317SG               VIA   -    MD0080PA00X+043444Y+015482X0180Y0180     S0      
317SG               VIA   -    MD0080PA00X+043444Y+016663X0180Y0180     S0      
317SG               VIA   -    MD0080PA00X+043444Y+016269X0180Y0180     S0      
317SG               VIA   -    MD0080PA00X+042656Y+015875X0180Y0180     S0      
317SG               VIA   -    MD0080PA00X+042656Y+013513X0180Y0180     S0      
317SG               VIA   -    MD0080PA00X+042656Y+016269X0180Y0180     S0      
317SG               VIA   -    MD0080PA00X+042656Y+016663X0180Y0180     S0      
317SG               VIA   -    MD0080PA00X+042263Y+015482X0180Y0180     S0      
317SG               VIA   -    MD0080PA00X+042263Y+014694X0180Y0180     S0      
317SG               VIA   -    MD0080PA00X+042263Y+016269X0180Y0180     S0      
317SG               VIA   -    MD0080PA00X+041869Y+015875X0180Y0180     S0      
317SG               VIA   -    MD0080PA00X+041475Y+015482X0180Y0180     S0      
317SG               VIA   -    MD0080PA00X+041475Y+013119X0180Y0180     S0      
317SG               VIA   -    MD0080PA00X+041082Y+015482X0180Y0180     S0      
317SG               VIA   -    MD0080PA00X+041082Y+015088X0180Y0180     S0      
317SG               VIA   -    MD0080PA00X+041082Y+014694X0180Y0180     S0      
317SG               VIA   -    MD0080PA00X+040688Y+014694X0180Y0180     S0      
317SG               VIA   -    MD0080PA00X+040294Y+014694X0180Y0180     S0      
317SG               VIA   -    MD0080PA00X+040294Y+014300X0180Y0180     S0      
317SG               VIA   -    MD0080PA00X+039900Y+014300X0180Y0180     S0      
317SG               VIA   -    MD0080PA00X+039900Y+013907X0180Y0180     S0      
317SG               VIA   -    MD0080PA00X+039507Y+013907X0180Y0180     S0      
317SG               VIA   -    MD0080PA00X+038719Y+021781X0180Y0180     S0      
317SG               VIA   -    MD0080PA00X+039113Y+020600X0180Y0180     S0      
317SG               VIA   -    MD0080PA00X+039507Y+019418X0180Y0180     S0      
317SG               VIA   -    MD0080PA00X+041082Y+018631X0180Y0180     S0      
317SG               VIA   -    MD0080PA00X+039900Y+018237X0180Y0180     S0      
317SG               VIA   -    MD0080PA00X+041869Y+017844X0180Y0180     S0      
317SG               VIA   -    MD0080PA00X+041082Y+017844X0180Y0180     S0      
317SG               VIA   -    MD0080PA00X+039900Y+017844X0180Y0180     S0      
317SG               VIA   -    MD0080PA00X+038719Y+017844X0180Y0180     S0      
317SG               VIA   -    MD0080PA00X+039507Y+017844X0180Y0180     S0      
317SG               VIA   -    MD0080PA00X+039113Y+017844X0180Y0180     S0      
317SG               VIA   -    MD0080PA00X+042263Y+017056X0180Y0180     S0      
317SG               VIA   -    MD0080PA00X+041475Y+017056X0180Y0180     S0      
317SG               VIA   -    MD0080PA00X+040688Y+017056X0180Y0180     S0      
317SG               VIA   -    MD0080PA00X+040294Y+017056X0180Y0180     S0      
317SG               VIA   -    MD0080PA00X+038719Y+017056X0180Y0180     S0      
317SG               VIA   -    MD0080PA00X+041869Y+016663X0180Y0180     S0      
317SG               VIA   -    MD0080PA00X+041082Y+016663X0180Y0180     S0      
317SG               VIA   -    MD0080PA00X+039507Y+016663X0180Y0180     S0      
317SG               VIA   -    MD0080PA00X+038719Y+016269X0180Y0180     S0      
317SG               VIA   -    MD0080PA00X+041475Y+016269X0180Y0180     S0      
317SG               VIA   -    MD0080PA00X+041082Y+016269X0180Y0180     S0      
317SG               VIA   -    MD0080PA00X+040294Y+016269X0180Y0180     S0      
317SG               VIA   -    MD0080PA00X+041082Y+015875X0180Y0180     S0      
317SG               VIA   -    MD0080PA00X+039900Y+015875X0180Y0180     S0      
317SG               VIA   -    MD0080PA00X+038719Y+015482X0180Y0180     S0      
317SG               VIA   -    MD0080PA00X+040294Y+015482X0180Y0180     S0      
317SG               VIA   -    MD0080PA00X+039507Y+015088X0180Y0180     S0      
317SG               VIA   -    MD0080PA00X+038719Y+014694X0180Y0180     S0      
317SG               VIA   -    MD0080PA00X+038719Y+013907X0180Y0180     S0      
317SG               VIA   -    MD0080PA00X+039113Y+013907X0180Y0180     S0      
317SG               VIA   -    MD0080PA00X+038719Y+013513X0180Y0180     S0      
317SG               VIA   -    MD0080PA00X+046987Y+021781X0180Y0180     S0      
317SG               VIA   -    MD0080PA00X+045806Y+021387X0180Y0180     S0      
317SG               VIA   -    MD0080PA00X+045018Y+019812X0180Y0180     S0      
317SG               VIA   -    MD0080PA00X+044625Y+020993X0180Y0180     S0      
317SG               VIA   -    MD0080PA00X+043837Y+019418X0180Y0180     S0      
317SG               VIA   -    MD0080PA00X+043444Y+020600X0180Y0180     S0      
317SG               VIA   -    MD0080PA00X+042263Y+019025X0180Y0180     S0      
317SG               VIA   -    MD0080PA00X+041869Y+020206X0180Y0180     S0      
317SG               VIA   -    MD0080PA00X+041475Y+021387X0180Y0180     S0      
317SG               VIA   -    MD0080PA00X+040688Y+019812X0180Y0180     S0      
317SG               VIA   -    MD0080PA00X+040294Y+020993X0180Y0180     S0      
317SG               VIA   -    MD0080PA00X+047381Y+020600X0180Y0180     S0      
317SG               VIA   -    MD0080PA00X+046200Y+020206X0180Y0180     S0      
317SG               VIA   -    MD0080PA00X+046593Y+019025X0180Y0180     S0      
317SG               VIA   -    MD0080PA00X+045412Y+018631X0180Y0180     S0      
317SG               VIA   -    MD0080PA00X+044231Y+018237X0180Y0180     S0      
317SG               VIA   -    MD0080PA00X+046987Y+017844X0180Y0180     S0      
317SG               VIA   -    MD0080PA00X+044625Y+017844X0180Y0180     S0      
317SG               VIA   -    MD0080PA00X+045018Y+017056X0180Y0180     S0      
317SG               VIA   -    MD0080PA00X+044231Y+017056X0180Y0180     S0      
317SG               VIA   -    MD0080PA00X+043444Y+017056X0180Y0180     S0      
317SG               VIA   -    MD0080PA00X+044625Y+016663X0180Y0180     S0      
317SG               VIA   -    MD0080PA00X+045806Y+016663X0180Y0180     S0      
317SG               VIA   -    MD0080PA00X+043837Y+016663X0180Y0180     S0      
317SG               VIA   -    MD0080PA00X+045018Y+016269X0180Y0180     S0      
317SG               VIA   -    MD0080PA00X+044231Y+016269X0180Y0180     S0      
317SG               VIA   -    MD0080PA00X+046200Y+015875X0180Y0180     S0      
317SG               VIA   -    MD0080PA00X+044625Y+015875X0180Y0180     S0      
317SG               VIA   -    MD0080PA00X+045018Y+015482X0180Y0180     S0      
317SG               VIA   -    MD0080PA00X+046593Y+014694X0180Y0180     S0      
327SG               SP1   -1          A10X+016355Y+040310X0050Y0240     S0      
327SG               C277  -2          A01X+009510Y+027280X0280Y0240     S1      
327SG               C278  -2          A01X+009505Y+026830X0280Y0240     S1      
327SG               C15   -2          A01X+022610Y+041040X0380Y0540R090 S1      
327SG               C14   -2          A01X+021860Y+041040X0380Y0540R090 S1      
327SG               C33   -2          A01X+016920Y+040910X0280Y0240     S1      
327SG               C30   -2          A01X+017140Y+041510X0380Y0540     S1      
327SG               U5    -8          A01X+017011Y+040201X0450Y0120R090 S1      
327SG               U5    -9          A01X+016795Y+040201X0450Y0120R090 S1      
327SG               U5    -10         A01X+016578Y+040201X0450Y0120R090 S1      
327SG               C12   -2          A01X+021760Y+038450X0280Y0240R270 S1      
327SG               C13   -2          A01X+022360Y+038280X0380Y0540R270 S1      
327SG               U5    -3          A01X+016578Y+039119X0450Y0120R090 S1      
327SG               U5    -4          A01X+016795Y+039119X0450Y0120R090 S1      
327SG               U5    -5          A01X+017011Y+039119X0450Y0120R090 S1      
327SG               C32   -2          A01X+017440Y+037760X0380Y0540     S1      
327SG               C41   -2          A01X+017120Y+038410X0280Y0240     S1      
317SG               VIA   -    MD0080PA00X+001288Y+002172X0180Y0180     S3      
317SG               VIA   -    MD0080PA00X+001688Y+002172X0180Y0180     S3      
317SG               VIA   -    MD0080PA00X+002088Y+002172X0180Y0180     S3      
317SG               VIA   -    MD0080PA00X+002488Y+002172X0180Y0180     S3      
317SG               VIA   -    MD0080PA00X+000841Y+043360X0180Y0180R180 S3      
317SG               VIA   -    MD0080PA00X+000441Y+043360X0180Y0180R180 S3      
317SG               VIA   -    MD0080PA00X+000400Y+042962X0180Y0180R270 S3      
317SG               VIA   -    MD0080PA00X+000400Y+042562X0180Y0180R270 S3      
317SG               VIA   -    MD0080PA00X+000400Y+042162X0180Y0180R270 S3      
317SG               VIA   -    MD0080PA00X+000400Y+041762X0180Y0180R270 S3      
317SG               VIA   -    MD0080PA00X+000400Y+041362X0180Y0180R270 S3      
317SG               VIA   -    MD0080PA00X+000400Y+040962X0180Y0180R270 S3      
317SG               VIA   -    MD0080PA00X+000400Y+040562X0180Y0180R270 S3      
317SG               VIA   -    MD0080PA00X+000400Y+040162X0180Y0180R270 S3      
317SG               VIA   -    MD0080PA00X+000400Y+039762X0180Y0180R270 S3      
317SG               VIA   -    MD0080PA00X+000400Y+039362X0180Y0180R270 S3      
317SG               VIA   -    MD0080PA00X+000400Y+038962X0180Y0180R270 S3      
317SG               VIA   -    MD0080PA00X+000400Y+038562X0180Y0180R270 S3      
317SG               VIA   -    MD0080PA00X+000400Y+038162X0180Y0180R270 S3      
317SG               VIA   -    MD0080PA00X+000400Y+037762X0180Y0180R270 S3      
317SG               VIA   -    MD0080PA00X+000400Y+037362X0180Y0180R270 S3      
317SG               VIA   -    MD0080PA00X+000400Y+036962X0180Y0180R270 S3      
317SG               VIA   -    MD0080PA00X+000400Y+036562X0180Y0180R270 S3      
317SG               VIA   -    MD0080PA00X+000400Y+036162X0180Y0180R270 S3      
317SG               VIA   -    MD0080PA00X+000400Y+035762X0180Y0180R270 S3      
317SG               VIA   -    MD0080PA00X+000400Y+035362X0180Y0180R270 S3      
317SG               VIA   -    MD0080PA00X+000400Y+034962X0180Y0180R270 S3      
317SG               VIA   -    MD0080PA00X+000400Y+034562X0180Y0180R270 S3      
317SG               VIA   -    MD0080PA00X+000400Y+034162X0180Y0180R270 S3      
317SG               VIA   -    MD0080PA00X+000400Y+033762X0180Y0180R270 S3      
317SG               VIA   -    MD0080PA00X+000400Y+029762X0180Y0180R270 S3      
317SG               VIA   -    MD0080PA00X+000400Y+029362X0180Y0180R270 S3      
317SG               VIA   -    MD0080PA00X+000400Y+028962X0180Y0180R270 S3      
317SG               VIA   -    MD0080PA00X+000400Y+004962X0180Y0180R270 S3      
317SG               VIA   -    MD0080PA00X+000400Y+004562X0180Y0180R270 S3      
317SG               VIA   -    MD0080PA00X+000400Y+004162X0180Y0180R270 S3      
317SG               VIA   -    MD0080PA00X+000400Y+003762X0180Y0180R270 S3      
317SG               VIA   -    MD0080PA00X+000400Y+003362X0180Y0180R270 S3      
317SG               VIA   -    MD0080PA00X+000400Y+002962X0180Y0180R270 S3      
317SG               VIA   -    MD0080PA00X+000400Y+002562X0180Y0180R270 S3      
317SG               VIA   -    MD0080PA00X+000488Y+002172X0180Y0180     S3      
317SG               VIA   -    MD0080PA00X+000888Y+002172X0180Y0180     S3      
317SG               VIA   -    MD0080PA00X+027641Y+043360X0180Y0180R180 S3      
317SG               VIA   -    MD0080PA00X+027241Y+043360X0180Y0180R180 S3      
317SG               VIA   -    MD0080PA00X+026841Y+043360X0180Y0180R180 S3      
317SG               VIA   -    MD0080PA00X+026441Y+043360X0180Y0180R180 S3      
317SG               VIA   -    MD0080PA00X+026041Y+043360X0180Y0180R180 S3      
317SG               VIA   -    MD0080PA00X+005506Y+004507X0180Y0180R090 S3      
317SG               VIA   -    MD0080PA00X+005556Y+004904X0180Y0180R159 S3      
317SG               VIA   -    MD0080PA00X+005786Y+005231X0180Y0180R130 S3      
317SG               VIA   -    MD0080PA00X+006146Y+005405X0180Y0180R101 S3      
317SG               VIA   -    MD0080PA00X+005506Y+002907X0180Y0180R090 S3      
317SG               VIA   -    MD0080PA00X+005506Y+003307X0180Y0180R090 S3      
317SG               VIA   -    MD0080PA00X+005506Y+003707X0180Y0180R090 S3      
317SG               VIA   -    MD0080PA00X+005506Y+004107X0180Y0180R090 S3      
317SG               VIA   -    MD0080PA00X+004888Y+002172X0180Y0180     S3      
317SG               VIA   -    MD0080PA00X+005288Y+002172X0180Y0180     S3      
317SG               VIA   -    MD0080PA00X+005506Y+002507X0180Y0180R090 S3      
317SG               VIA   -    MD0080PA00X+004441Y+043360X0180Y0180R180 S3      
317SG               VIA   -    MD0080PA00X+004041Y+043360X0180Y0180R180 S3      
317SG               VIA   -    MD0080PA00X+003641Y+043360X0180Y0180R180 S3      
317SG               VIA   -    MD0080PA00X+003241Y+043360X0180Y0180R180 S3      
317SG               VIA   -    MD0080PA00X+002888Y+002172X0180Y0180     S3      
317SG               VIA   -    MD0080PA00X+003288Y+002172X0180Y0180     S3      
317SG               VIA   -    MD0080PA00X+003688Y+002172X0180Y0180     S3      
317SG               VIA   -    MD0080PA00X+004088Y+002172X0180Y0180     S3      
317SG               VIA   -    MD0080PA00X+004488Y+002172X0180Y0180     S3      
317SG               VIA   -    MD0080PA00X+002841Y+043360X0180Y0180R180 S3      
317SG               VIA   -    MD0080PA00X+002441Y+043360X0180Y0180R180 S3      
317SG               VIA   -    MD0080PA00X+002041Y+043360X0180Y0180R180 S3      
317SG               VIA   -    MD0080PA00X+001641Y+043360X0180Y0180R180 S3      
317SG               VIA   -    MD0080PA00X+001241Y+043360X0180Y0180R180 S3      
317SG               VIA   -    MD0100PA00X+008890Y+006700X0200Y0200     S3      
327SG               U7    -2          A01X+009575Y+006910X0200Y0470R090 S1      
317SG               VIA   -    MD0080PA00X+006546Y+005420X0180Y0180     S3      
317SG               VIA   -    MD0080PA00X+006946Y+005420X0180Y0180     S3      
317SG               VIA   -    MD0080PA00X+007346Y+005420X0180Y0180     S3      
317SG               VIA   -    MD0080PA00X+007746Y+005420X0180Y0180     S3      
317SG               VIA   -    MD0080PA00X+008146Y+005420X0180Y0180     S3      
317SG               VIA   -    MD0080PA00X+006441Y+043360X0180Y0180R180 S3      
317SG               VIA   -    MD0080PA00X+006041Y+043360X0180Y0180R180 S3      
317SG               VIA   -    MD0080PA00X+005641Y+043360X0180Y0180R180 S3      
317SG               VIA   -    MD0080PA00X+005241Y+043360X0180Y0180R180 S3      
317SG               VIA   -    MD0080PA00X+004841Y+043360X0180Y0180R180 S3      
317SG               VIA   -    MD0100PA00X+008575Y+020275X0200Y0200R180 S3      
327SG               J18   -1          A01X+008621Y+020910X0410Y0870R180 S1      
317SG               VIA   -    MD0100PA00X+011950Y+005769X0200Y0200     S3      
327SG               C225  -2          A01X+012157Y+006136X0280Y0240     S1      
317SG               VIA   -    MD0080PA00X+008546Y+005420X0180Y0180     S3      
317SG               VIA   -    MD0080PA00X+008946Y+005420X0180Y0180     S3      
317SG               VIA   -    MD0080PA00X+009346Y+005420X0180Y0180     S3      
317SG               VIA   -    MD0080PA00X+009746Y+005420X0180Y0180     S3      
317SG               VIA   -    MD0080PA00X+008041Y+043360X0180Y0180R180 S3      
317SG               VIA   -    MD0080PA00X+007641Y+043360X0180Y0180R180 S3      
317SG               VIA   -    MD0080PA00X+007241Y+043360X0180Y0180R180 S3      
317SG               VIA   -    MD0080PA00X+006841Y+043360X0180Y0180R180 S3      
317SG               VIA   -    MD0100PA00X+006600Y+041900X0200Y0200     S3      
317SG               VIA   -    MD0080PA00X+006700Y+028310X0180Y0180     S3      
317SG               VIA   -    MD0080PA00X+007925Y+026610X0180Y0180R270 S3      
327SG               U28   -9          A01X+008200Y+026610X0140Y0110R180 S1      
317SG               VIA   -    MD0100PA00X+008015Y+025365X0200Y0200     S3      
317SG               VIA   -    MD0100PA00X+007150Y+024780X0200Y0200     S3      
327SG               C312  -2          A01X+007150Y+024440X0280Y0240R090 S1      
317SG               VIA   -    MD0100PA00X+007140Y+022170X0200Y0200     S3      
327SG               C313  -2          A01X+007140Y+022520X0280Y0240R270 S1      
317SG               VIA   -    MD0100PA00X+007459Y+020221X0200Y0200R180 S3      
327SG               J18   -3          A01X+007459Y+020910X0410Y0870R180 S1      
317SG               VIA   -    MD0080PA00X+010146Y+005420X0180Y0180     S3      
317SG               VIA   -    MD0080PA00X+010546Y+005420X0180Y0180     S3      
317SG               VIA   -    MD0080PA00X+010946Y+005420X0180Y0180     S3      
317SG               VIA   -    MD0080PA00X+011346Y+005420X0180Y0180     S3      
317SG               VIA   -    MD0080PA00X+011746Y+005420X0180Y0180     S3      
317SG               VIA   -    MD0080PA00X+010041Y+043360X0180Y0180R180 S3      
317SG               VIA   -    MD0080PA00X+009641Y+043360X0180Y0180R180 S3      
317SG               VIA   -    MD0080PA00X+009241Y+043360X0180Y0180R180 S3      
317SG               VIA   -    MD0080PA00X+008841Y+043360X0180Y0180R180 S3      
317SG               VIA   -    MD0080PA00X+008441Y+043360X0180Y0180R180 S3      
317SG               VIA   -    MD0100PA00X+010250Y+042000X0200Y0200     S3      
317SG               VIA   -    MD0100PA00X+009400Y+042000X0200Y0200     S3      
317SG               VIA   -    MD0080PA00X+008580Y+028745X0180Y0180     S3      
317SG               VIA   -    MD0100PA00X+009880Y+027240X0200Y0200R270 S3      
317SG               VIA   -    MD0100PA00X+009870Y+026830X0200Y0200R270 S3      
317SG               VIA   -    MD0080PA00X+008560Y+026370X0180Y0180R180 S3      
327SG               U28   -8          A01X+008200Y+026413X0140Y0110R180 S1      
317SG               VIA   -    MD0100PA00X+009303Y+024648X0200Y0200     S3      
317SG               VIA   -    MD0100PA00X+008720Y+025830X0200Y0200R270 S3      
327SG               C276  -2          A01X+009070Y+025805X0280Y0240R180 S1      
317SG               VIA   -    MD0080PA00X+008680Y+023000X0180Y0180     S3      
327SG               U32   -4          A01X+008594Y+022465X0180Y0600R180 S1      
317SG               VIA   -    MD0100PA00X+014010Y+039560X0200Y0200     S3      
327SG               R48   -2          A10X+014350Y+039460X0280Y0240     S2      
327SG               C29   -2          A01X+014350Y+039460X0280Y0240R180 S1      
317SG               VIA   -    MD0100PA00X+014012Y+039160X0200Y0200R180 S3      
327SG               C75   -1          A01X+014506Y+039010X0120Y0150     S1      
317SG               VIA   -    MD0100PA00X+014800Y+037000X0200Y0200R180 S3      
317SG               VIA   -    MD0080PA00X+013816Y+002172X0180Y0180     S3      
317SG               VIA   -    MD0080PA00X+014216Y+002172X0180Y0180     S3      
317SG               VIA   -    MD0080PA00X+014616Y+002172X0180Y0180     S3      
317SG               VIA   -    MD0080PA00X+015016Y+002172X0180Y0180     S3      
317SG               VIA   -    MD0080PA00X+015416Y+002172X0180Y0180     S3      
317SG               VIA   -    MD0080PA00X+013641Y+043360X0180Y0180R180 S3      
317SG               VIA   -    MD0080PA00X+013241Y+043360X0180Y0180R180 S3      
317SG               VIA   -    MD0080PA00X+012841Y+043360X0180Y0180R180 S3      
317SG               VIA   -    MD0080PA00X+012441Y+043360X0180Y0180R180 S3      
317SG               VIA   -    MD0080PA00X+012041Y+043360X0180Y0180R180 S3      
317SG               VIA   -    MD0100PA00X+015150Y+037000X0200Y0200R180 S3      
317SG               VIA   -    MD0080PA00X+013850Y+007500X0180Y0180     S3      
317SG               VIA   -    MD0080PA00X+014400Y+006250X0180Y0180     S3      
317SG               VIA   -    MD0080PA00X+015184Y+007994X0180Y0180     S3      
317SG               VIA   -    MD0080PA00X+012146Y+005420X0180Y0180     S3      
317SG               VIA   -    MD0080PA00X+012546Y+005420X0180Y0180     S3      
317SG               VIA   -    MD0080PA00X+012945Y+005392X0180Y0180R075 S3      
317SG               VIA   -    MD0080PA00X+013292Y+005193X0180Y0180R046 S3      
317SG               VIA   -    MD0080PA00X+013498Y+004850X0180Y0180R016 S3      
317SG               VIA   -    MD0080PA00X+013530Y+004451X0180Y0180R270 S3      
317SG               VIA   -    MD0080PA00X+013530Y+004051X0180Y0180R270 S3      
317SG               VIA   -    MD0080PA00X+013530Y+003651X0180Y0180R270 S3      
317SG               VIA   -    MD0080PA00X+013530Y+003251X0180Y0180R270 S3      
317SG               VIA   -    MD0080PA00X+013530Y+002851X0180Y0180R270 S3      
317SG               VIA   -    MD0080PA00X+013530Y+002451X0180Y0180R270 S3      
317SG               VIA   -    MD0080PA00X+011641Y+043360X0180Y0180R180 S3      
317SG               VIA   -    MD0080PA00X+011241Y+043360X0180Y0180R180 S3      
317SG               VIA   -    MD0080PA00X+010841Y+043360X0180Y0180R180 S3      
317SG               VIA   -    MD0080PA00X+010441Y+043360X0180Y0180R180 S3      
317SG               VIA   -    MD0080PA00X+019641Y+043360X0180Y0180R180 S3      
317SG               VIA   -    MD0080PA00X+019241Y+043360X0180Y0180R180 S3      
317SG               VIA   -    MD0100PA00X+019150Y+041300X0200Y0200     S3      
327SG               R33   -2          A10X+018730Y+041300X0380Y0540R180 S2      
327SG               U2    -4          A01X+018832Y+007400X0200Y0650R270 S1      
317SG               VIA   -    MD0080PA00X+018841Y+043360X0180Y0180R180 S3      
317SG               VIA   -    MD0080PA00X+018441Y+043360X0180Y0180R180 S3      
317SG               VIA   -    MD0080PA00X+018041Y+043360X0180Y0180R180 S3      
317SG               VIA   -    MD0080PA00X+017641Y+043360X0180Y0180R180 S3      
317SG               VIA   -    MD0100PA00X+017460Y+040610X0200Y0200R270 S3      
317SG               VIA   -    MD0100PA00X+017460Y+041060X0200Y0200R270 S3      
317SG               VIA   -    MD0100PA00X+017510Y+038710X0200Y0200R180 S3      
317SG               VIA   -    MD0100PA00X+017460Y+040160X0200Y0200R270 S3      
317SG               VIA   -    MD0100PA00X+017510Y+038260X0200Y0200R180 S3      
317SG               VIA   -    MD0100PA00X+017860Y+037460X0200Y0200R180 S3      
317SG               VIA   -    MD0100PA00X+017860Y+037860X0200Y0200R180 S3      
317SG               VIA   -    MD0080PA00X+020966Y+033150X0180Y0180R270 S3      
317SG               VIA   -    MD0080PA00X+017241Y+043360X0180Y0180R180 S3      
317SG               VIA   -    MD0080PA00X+016841Y+043360X0180Y0180R180 S3      
317SG               VIA   -    MD0080PA00X+016441Y+043360X0180Y0180R180 S3      
317SG               VIA   -    MD0080PA00X+016041Y+043360X0180Y0180R180 S3      
317SG               VIA   -    MD0080PA00X+015641Y+043360X0180Y0180R180 S3      
317SG               VIA   -    MD0080PA00X+016710Y+040560X0180Y0180R180 S3      
317SG               VIA   -    MD0100PA00X+015086Y+006740X0200Y0200     S3      
327SG               C17   -2          A01X+015480Y+006632X0280Y0240R090 S1      
317SG               VIA   -    MD0080PA00X+015911Y+004565X0180Y0180R166 S3      
317SG               VIA   -    MD0080PA00X+016074Y+004931X0180Y0180R146 S3      
317SG               VIA   -    MD0080PA00X+015880Y+002967X0180Y0180R090 S3      
317SG               VIA   -    MD0080PA00X+015880Y+003367X0180Y0180R090 S3      
317SG               VIA   -    MD0080PA00X+015880Y+003767X0180Y0180R090 S3      
317SG               VIA   -    MD0080PA00X+015880Y+004167X0180Y0180R090 S3      
317SG               VIA   -    MD0080PA00X+015816Y+002172X0180Y0180     S3      
317SG               VIA   -    MD0080PA00X+015880Y+002567X0180Y0180R090 S3      
317SG               VIA   -    MD0080PA00X+015241Y+043360X0180Y0180R180 S3      
317SG               VIA   -    MD0080PA00X+014841Y+043360X0180Y0180R180 S3      
317SG               VIA   -    MD0080PA00X+014441Y+043360X0180Y0180R180 S3      
317SG               VIA   -    MD0080PA00X+014041Y+043360X0180Y0180R180 S3      
317SG               VIA   -    MD0080PA00X+025641Y+043360X0180Y0180R180 S3      
317SG               VIA   -    MD0080PA00X+025241Y+043360X0180Y0180R180 S3      
317SG               VIA   -    MD0080PA00X+024841Y+043360X0180Y0180R180 S3      
317SG               VIA   -    MD0080PA00X+024441Y+043360X0180Y0180R180 S3      
317SG               VIA   -    MD0080PA00X+024041Y+043360X0180Y0180R180 S3      
317SG               VIA   -    MD0080PA00X+023641Y+043360X0180Y0180R180 S3      
317SG               VIA   -    MD0080PA00X+023241Y+043360X0180Y0180R180 S3      
317SG               VIA   -    MD0080PA00X+022841Y+043360X0180Y0180R180 S3      
317SG               VIA   -    MD0100PA00X+022950Y+041500X0200Y0200R270 S3      
317SG               VIA   -    MD0100PA00X+022850Y+038250X0200Y0200R270 S3      
317SG               VIA   -    MD0080PA00X+022441Y+043360X0180Y0180R180 S3      
317SG               VIA   -    MD0080PA00X+022041Y+043360X0180Y0180R180 S3      
317SG               VIA   -    MD0080PA00X+021641Y+043360X0180Y0180R180 S3      
317SG               VIA   -    MD0080PA00X+021241Y+043360X0180Y0180R180 S3      
317SG               VIA   -    MD0100PA00X+021760Y+041510X0200Y0200R180 S3      
317SG               VIA   -    MD0100PA00X+022560Y+041510X0200Y0200R180 S3      
317SG               VIA   -    MD0100PA00X+022150Y+041500X0200Y0200R270 S3      
317SG               VIA   -    MD0100PA00X+021800Y+038110X0200Y0200R270 S3      
317SG               VIA   -    MD0080PA00X+022180Y+028950X0180Y0180R270 S3      
327SG               C306  -1          A01X+022180Y+029310X0280Y0240R090 S1      
317SG               VIA   -    MD0080PA00X+021730Y+028950X0180Y0180R270 S3      
317SG               VIA   -    MD0080PA00X+020830Y+028950X0180Y0180R270 S3      
327SG               R413  -2   M      A10X+021280Y+029310X0280Y0240R090 S2      
327SG               R409  -2   M      A10X+020830Y+029310X0280Y0240R090 S2      
327SG               R416  -2   M      A10X+021730Y+029310X0280Y0240R090 S2      
317SG               VIA   -    MD0080PA00X+020841Y+043360X0180Y0180R180 S3      
317SG               VIA   -    MD0080PA00X+020441Y+043360X0180Y0180R180 S3      
317SG               VIA   -    MD0080PA00X+020041Y+043360X0180Y0180R180 S3      
317SG               ME9   -8   MD0120PA00X+002270Y+037986X0240Y0240     S3      
317SG               ME9   -7   MD0120PA00X+001988Y+037303X0240Y0240     S3      
317SG               ME9   -6   MD0120PA00X+002270Y+036621X0240Y0240     S3      
317SG               ME9   -5   MD0120PA00X+002953Y+036338X0240Y0240     S3      
317SG               ME9   -4   MD0120PA00X+003635Y+036621X0240Y0240     S3      
317SG               ME9   -3   MD0120PA00X+003918Y+037303X0240Y0240     S3      
317SG               ME9   -2   MD0120PA00X+003635Y+037986X0240Y0240     S3      
317SG               ME9   -1   MD0120PA00X+002953Y+038268X0240Y0240     S3      
317SG               VIA   -    MD0080PA00X+061996Y+022127X0180Y0180     S3      
317SG               VIA   -    MD0080PA00X+061996Y+023087X0180Y0180     S3      
317SG               VIA   -    MD0080PA00X+043445Y+011660X0180Y0180     S3      
317SG               VIA   -    MD0080PA00X+044405Y+011660X0180Y0180     S3      
317SG               VIA   -    MD0080PA00X+034530Y+019630X0180Y0180     S3      
317SG               VIA   -    MD0080PA00X+036510Y+019476X0180Y0180     S3      
317SG               VIA   -    MD0100PA00X+044400Y+026300X0200Y0200     S3      
317SG               VIA   -    MD0100PA00X+043950Y+026650X0200Y0200     S3      
327SG               C232  -2          A01X+044550Y+026720X0380Y0540R270 S1      
327SG               C233  -2          A01X+043900Y+026990X0280Y0240R270 S1      
327SG               C229  -2          A10X+045660Y+028450X0280Y0240R180 S2      
327SG               C294  -2          A10X+045660Y+028950X0280Y0240R180 S2      
317SG               VIA   -    MD0100PA00X+046000Y+028950X0200Y0200     S3      
317SG               VIA   -    MD0100PA00X+046000Y+028450X0200Y0200     S3      
327SG               R253  -2          A10X+057530Y+019900X0380Y0540R180 S2      
327SG               R39   -2          A10X+031850Y+037570X0380Y0540R090 S2      
327SG               C257  -2          A01X+057600Y+020870X0380Y0540R270 S1      
317SG               VIA   -    MD0100PA00X+034200Y+037600X0200Y0200     S3      
317SG               VIA   -    MD0100PA00X+033850Y+037600X0200Y0200     S3      
317SG               VIA   -    MD0100PA00X+033150Y+037600X0200Y0200     S3      
317SG               VIA   -    MD0100PA00X+032600Y+037400X0200Y0200     S3      
327SG               C20   -2          A01X+034800Y+037180X0380Y0540R090 S1      
327SG               C22   -2          A01X+034000Y+037180X0380Y0540R090 S1      
327SG               C18   -2          A01X+032550Y+037060X0280Y0240R090 S1      
327SG               C21   -2          A01X+033200Y+037180X0380Y0540R090 S1      
317SG               VIA   -    MD0080PA00X+065604Y+018120X0180Y0180R090 S3      
317SG               VIA   -    MD0080PA00X+065604Y+017720X0180Y0180R090 S3      
317SG               VIA   -    MD0080PA00X+065604Y+017320X0180Y0180R090 S3      
317SG               VIA   -    MD0080PA00X+065604Y+016920X0180Y0180R090 S3      
317SG               VIA   -    MD0080PA00X+065604Y+016520X0180Y0180R090 S3      
317SG               VIA   -    MD0080PA00X+065604Y+016120X0180Y0180R090 S3      
317SG               VIA   -    MD0080PA00X+065604Y+015720X0180Y0180R090 S3      
317SG               VIA   -    MD0080PA00X+065604Y+015320X0180Y0180R090 S3      
317SG               VIA   -    MD0080PA00X+065604Y+014920X0180Y0180R090 S3      
317SG               VIA   -    MD0080PA00X+065604Y+014520X0180Y0180R090 S3      
317SG               VIA   -    MD0080PA00X+065604Y+010520X0180Y0180R090 S3      
317SG               VIA   -    MD0080PA00X+065604Y+010120X0180Y0180R090 S3      
317SG               VIA   -    MD0080PA00X+065604Y+009720X0180Y0180R090 S3      
317SG               VIA   -    MD0080PA00X+065604Y+009320X0180Y0180R090 S3      
317SG               VIA   -    MD0080PA00X+065604Y+008920X0180Y0180R090 S3      
317SG               VIA   -    MD0080PA00X+065604Y+008520X0180Y0180R090 S3      
317SG               VIA   -    MD0080PA00X+065604Y+008120X0180Y0180R090 S3      
317SG               VIA   -    MD0080PA00X+065604Y+007720X0180Y0180R090 S3      
317SG               VIA   -    MD0080PA00X+065604Y+007320X0180Y0180R090 S3      
317SG               VIA   -    MD0080PA00X+065604Y+006920X0180Y0180R090 S3      
317SG               VIA   -    MD0080PA00X+065604Y+006520X0180Y0180R090 S3      
317SG               VIA   -    MD0080PA00X+065604Y+006120X0180Y0180R090 S3      
317SG               VIA   -    MD0080PA00X+065604Y+005720X0180Y0180R090 S3      
317SG               VIA   -    MD0080PA00X+065340Y+005420X0180Y0180     S3      
317SG               VIA   -    MD0080PA00X+064940Y+005420X0180Y0180     S3      
317SG               VIA   -    MD0080PA00X+062940Y+005420X0180Y0180     S3      
317SG               VIA   -    MD0080PA00X+062540Y+005420X0180Y0180     S3      
317SG               VIA   -    MD0080PA00X+062140Y+005420X0180Y0180     S3      
317SG               VIA   -    MD0080PA00X+061740Y+005420X0180Y0180     S3      
317SG               VIA   -    MD0080PA00X+061340Y+005420X0180Y0180     S3      
317SG               VIA   -    MD0080PA00X+060940Y+005420X0180Y0180     S3      
317SG               VIA   -    MD0080PA00X+060540Y+005420X0180Y0180     S3      
317SG               VIA   -    MD0080PA00X+060140Y+005420X0180Y0180     S3      
317SG               VIA   -    MD0080PA00X+059740Y+005420X0180Y0180     S3      
317SG               VIA   -    MD0080PA00X+059340Y+005420X0180Y0180     S3      
317SG               VIA   -    MD0080PA00X+058940Y+005420X0180Y0180     S3      
317SG               VIA   -    MD0080PA00X+058540Y+005420X0180Y0180     S3      
317SG               VIA   -    MD0080PA00X+058140Y+005420X0180Y0180     S3      
317SG               VIA   -    MD0080PA00X+057740Y+005420X0180Y0180     S3      
317SG               VIA   -    MD0080PA00X+057340Y+005420X0180Y0180     S3      
317SG               VIA   -    MD0080PA00X+056940Y+005420X0180Y0180     S3      
317SG               VIA   -    MD0080PA00X+056540Y+005420X0180Y0180     S3      
317SG               VIA   -    MD0080PA00X+056140Y+005420X0180Y0180     S3      
317SG               VIA   -    MD0080PA00X+055740Y+005420X0180Y0180     S3      
317SG               VIA   -    MD0080PA00X+055340Y+005420X0180Y0180     S3      
317SG               VIA   -    MD0080PA00X+054940Y+005420X0180Y0180     S3      
317SG               VIA   -    MD0080PA00X+054540Y+005420X0180Y0180     S3      
317SG               VIA   -    MD0080PA00X+054140Y+005420X0180Y0180     S3      
317SG               VIA   -    MD0080PA00X+053740Y+005420X0180Y0180     S3      
317SG               VIA   -    MD0080PA00X+053340Y+005420X0180Y0180     S3      
317SG               VIA   -    MD0080PA00X+052940Y+005420X0180Y0180     S3      
317SG               VIA   -    MD0080PA00X+052540Y+005420X0180Y0180     S3      
317SG               VIA   -    MD0080PA00X+052140Y+005420X0180Y0180     S3      
317SG               VIA   -    MD0080PA00X+051740Y+005420X0180Y0180     S3      
317SG               VIA   -    MD0080PA00X+051340Y+005420X0180Y0180     S3      
317SG               VIA   -    MD0080PA00X+050940Y+005420X0180Y0180     S3      
317SG               VIA   -    MD0080PA00X+050540Y+005420X0180Y0180     S3      
317SG               VIA   -    MD0080PA00X+050140Y+005420X0180Y0180     S3      
317SG               VIA   -    MD0080PA00X+049740Y+005420X0180Y0180     S3      
317SG               VIA   -    MD0080PA00X+049340Y+005420X0180Y0180     S3      
317SG               VIA   -    MD0080PA00X+048940Y+005420X0180Y0180     S3      
317SG               VIA   -    MD0080PA00X+048540Y+005420X0180Y0180     S3      
317SG               VIA   -    MD0080PA00X+048140Y+005420X0180Y0180     S3      
317SG               VIA   -    MD0080PA00X+047740Y+005420X0180Y0180     S3      
317SG               VIA   -    MD0080PA00X+047340Y+005420X0180Y0180     S3      
317SG               VIA   -    MD0080PA00X+046940Y+005420X0180Y0180     S3      
317SG               VIA   -    MD0080PA00X+046540Y+005420X0180Y0180     S3      
317SG               VIA   -    MD0080PA00X+046140Y+005420X0180Y0180     S3      
317SG               VIA   -    MD0080PA00X+045740Y+005420X0180Y0180     S3      
317SG               VIA   -    MD0080PA00X+045340Y+005420X0180Y0180     S3      
317SG               VIA   -    MD0080PA00X+044940Y+005420X0180Y0180     S3      
317SG               VIA   -    MD0080PA00X+044540Y+005420X0180Y0180     S3      
317SG               VIA   -    MD0080PA00X+044140Y+005420X0180Y0180     S3      
317SG               VIA   -    MD0080PA00X+043740Y+005420X0180Y0180     S3      
317SG               VIA   -    MD0080PA00X+043340Y+005420X0180Y0180     S3      
317SG               VIA   -    MD0080PA00X+042940Y+005420X0180Y0180     S3      
317SG               VIA   -    MD0080PA00X+042540Y+005420X0180Y0180     S3      
317SG               VIA   -    MD0080PA00X+042140Y+005420X0180Y0180     S3      
317SG               VIA   -    MD0080PA00X+041740Y+005420X0180Y0180     S3      
317SG               VIA   -    MD0080PA00X+028041Y+043360X0180Y0180R180 S3      
317SG               VIA   -    MD0080PA00X+028441Y+043360X0180Y0180R180 S3      
317SG               VIA   -    MD0080PA00X+028841Y+043360X0180Y0180R180 S3      
317SG               VIA   -    MD0080PA00X+029241Y+043360X0180Y0180R180 S3      
317SG               VIA   -    MD0080PA00X+029641Y+043360X0180Y0180R180 S3      
317SG               VIA   -    MD0080PA00X+030041Y+043360X0180Y0180R180 S3      
317SG               VIA   -    MD0080PA00X+030441Y+043360X0180Y0180R180 S3      
317SG               VIA   -    MD0080PA00X+030841Y+043360X0180Y0180R180 S3      
317SG               VIA   -    MD0080PA00X+031241Y+043360X0180Y0180R180 S3      
317SG               VIA   -    MD0080PA00X+031641Y+043360X0180Y0180R180 S3      
317SG               VIA   -    MD0080PA00X+032041Y+043360X0180Y0180R180 S3      
317SG               VIA   -    MD0080PA00X+032441Y+043360X0180Y0180R180 S3      
317SG               VIA   -    MD0080PA00X+032841Y+043360X0180Y0180R180 S3      
317SG               VIA   -    MD0080PA00X+033241Y+043360X0180Y0180R180 S3      
317SG               VIA   -    MD0080PA00X+033641Y+043360X0180Y0180R180 S3      
317SG               VIA   -    MD0080PA00X+034041Y+043360X0180Y0180R180 S3      
317SG               VIA   -    MD0080PA00X+034441Y+043360X0180Y0180R180 S3      
317SG               VIA   -    MD0080PA00X+034841Y+043360X0180Y0180R180 S3      
317SG               VIA   -    MD0080PA00X+035241Y+043360X0180Y0180R180 S3      
317SG               VIA   -    MD0080PA00X+035641Y+043360X0180Y0180R180 S3      
317SG               VIA   -    MD0080PA00X+036041Y+043360X0180Y0180R180 S3      
317SG               VIA   -    MD0080PA00X+036441Y+043360X0180Y0180R180 S3      
317SG               VIA   -    MD0080PA00X+036841Y+043360X0180Y0180R180 S3      
317SG               VIA   -    MD0080PA00X+037241Y+043360X0180Y0180R180 S3      
317SG               VIA   -    MD0080PA00X+037641Y+043360X0180Y0180R180 S3      
317SG               VIA   -    MD0080PA00X+038041Y+043360X0180Y0180R180 S3      
317SG               VIA   -    MD0080PA00X+038441Y+043360X0180Y0180R180 S3      
317SG               VIA   -    MD0080PA00X+038841Y+043360X0180Y0180R180 S3      
317SG               VIA   -    MD0080PA00X+039241Y+043360X0180Y0180R180 S3      
317SG               VIA   -    MD0080PA00X+039641Y+043360X0180Y0180R180 S3      
317SG               VIA   -    MD0080PA00X+040041Y+043360X0180Y0180R180 S3      
317SG               VIA   -    MD0080PA00X+040441Y+043360X0180Y0180R180 S3      
317SG               VIA   -    MD0080PA00X+040841Y+043360X0180Y0180R180 S3      
317SG               VIA   -    MD0080PA00X+041241Y+043360X0180Y0180R180 S3      
317SG               VIA   -    MD0080PA00X+041641Y+043360X0180Y0180R180 S3      
317SG               VIA   -    MD0080PA00X+042041Y+043360X0180Y0180R180 S3      
317SG               VIA   -    MD0080PA00X+042441Y+043360X0180Y0180R180 S3      
317SG               VIA   -    MD0080PA00X+042841Y+043360X0180Y0180R180 S3      
317SG               VIA   -    MD0080PA00X+043241Y+043360X0180Y0180R180 S3      
317SG               VIA   -    MD0080PA00X+043641Y+043360X0180Y0180R180 S3      
317SG               VIA   -    MD0080PA00X+044041Y+043360X0180Y0180R180 S3      
317SG               VIA   -    MD0080PA00X+044441Y+043360X0180Y0180R180 S3      
317SG               VIA   -    MD0080PA00X+044841Y+043360X0180Y0180R180 S3      
317SG               VIA   -    MD0080PA00X+045241Y+043360X0180Y0180R180 S3      
317SG               VIA   -    MD0080PA00X+045641Y+043360X0180Y0180R180 S3      
317SG               VIA   -    MD0080PA00X+046041Y+043360X0180Y0180R180 S3      
317SG               VIA   -    MD0080PA00X+046441Y+043360X0180Y0180R180 S3      
317SG               VIA   -    MD0080PA00X+046841Y+043360X0180Y0180R180 S3      
317SG               VIA   -    MD0080PA00X+047241Y+043360X0180Y0180R180 S3      
317SG               VIA   -    MD0080PA00X+047641Y+043360X0180Y0180R180 S3      
317SG               VIA   -    MD0080PA00X+048041Y+043360X0180Y0180R180 S3      
317SG               VIA   -    MD0080PA00X+048441Y+043360X0180Y0180R180 S3      
317SG               VIA   -    MD0080PA00X+048841Y+043360X0180Y0180R180 S3      
317SG               VIA   -    MD0080PA00X+049241Y+043360X0180Y0180R180 S3      
317SG               VIA   -    MD0080PA00X+049641Y+043360X0180Y0180R180 S3      
317SG               VIA   -    MD0080PA00X+050041Y+043360X0180Y0180R180 S3      
317SG               VIA   -    MD0080PA00X+050441Y+043360X0180Y0180R180 S3      
317SG               VIA   -    MD0080PA00X+050841Y+043360X0180Y0180R180 S3      
317SG               VIA   -    MD0080PA00X+051241Y+043360X0180Y0180R180 S3      
317SG               VIA   -    MD0080PA00X+051641Y+043360X0180Y0180R180 S3      
317SG               VIA   -    MD0080PA00X+052041Y+043360X0180Y0180R180 S3      
317SG               VIA   -    MD0080PA00X+052441Y+043360X0180Y0180R180 S3      
317SG               VIA   -    MD0080PA00X+052841Y+043360X0180Y0180R180 S3      
317SG               VIA   -    MD0080PA00X+053241Y+043360X0180Y0180R180 S3      
317SG               VIA   -    MD0080PA00X+053641Y+043360X0180Y0180R180 S3      
317SG               VIA   -    MD0080PA00X+054041Y+043360X0180Y0180R180 S3      
317SG               VIA   -    MD0080PA00X+054441Y+043360X0180Y0180R180 S3      
317SG               VIA   -    MD0080PA00X+054841Y+043360X0180Y0180R180 S3      
317SG               VIA   -    MD0080PA00X+055241Y+043360X0180Y0180R180 S3      
317SG               VIA   -    MD0080PA00X+055641Y+043360X0180Y0180R180 S3      
317SG               VIA   -    MD0080PA00X+056041Y+043360X0180Y0180R180 S3      
317SG               VIA   -    MD0080PA00X+056441Y+043360X0180Y0180R180 S3      
317SG               VIA   -    MD0080PA00X+056841Y+043360X0180Y0180R180 S3      
317SG               VIA   -    MD0080PA00X+057241Y+043360X0180Y0180R180 S3      
317SG               VIA   -    MD0080PA00X+057641Y+043360X0180Y0180R180 S3      
317SG               VIA   -    MD0080PA00X+058041Y+043360X0180Y0180R180 S3      
317SG               VIA   -    MD0080PA00X+058441Y+043360X0180Y0180R180 S3      
317SG               VIA   -    MD0080PA00X+058841Y+043360X0180Y0180R180 S3      
317SG               VIA   -    MD0080PA00X+059241Y+043360X0180Y0180R180 S3      
317SG               VIA   -    MD0080PA00X+059641Y+043360X0180Y0180R180 S3      
317SG               VIA   -    MD0080PA00X+060041Y+043360X0180Y0180R180 S3      
317SG               VIA   -    MD0080PA00X+060441Y+043360X0180Y0180R180 S3      
317SG               VIA   -    MD0080PA00X+060841Y+043360X0180Y0180R180 S3      
317SG               VIA   -    MD0080PA00X+061241Y+043360X0180Y0180R180 S3      
317SG               VIA   -    MD0080PA00X+061641Y+043360X0180Y0180R180 S3      
317SG               VIA   -    MD0080PA00X+062041Y+043360X0180Y0180R180 S3      
317SG               VIA   -    MD0080PA00X+062441Y+043360X0180Y0180R180 S3      
317SG               VIA   -    MD0080PA00X+062841Y+043360X0180Y0180R180 S3      
317SG               VIA   -    MD0080PA00X+063241Y+043360X0180Y0180R180 S3      
317SG               VIA   -    MD0080PA00X+063641Y+043360X0180Y0180R180 S3      
317SG               VIA   -    MD0080PA00X+064041Y+043360X0180Y0180R180 S3      
317SG               VIA   -    MD0080PA00X+064441Y+043360X0180Y0180R180 S3      
317SG               VIA   -    MD0080PA00X+064841Y+043360X0180Y0180R180 S3      
317SG               VIA   -    MD0080PA00X+065241Y+043360X0180Y0180R180 S3      
317SG               VIA   -    MD0080PA00X+065604Y+043191X0180Y0180R090 S3      
317SG               VIA   -    MD0080PA00X+065604Y+042791X0180Y0180R090 S3      
317SG               VIA   -    MD0080PA00X+065604Y+042391X0180Y0180R090 S3      
317SG               VIA   -    MD0080PA00X+065604Y+041991X0180Y0180R090 S3      
317SG               VIA   -    MD0080PA00X+065604Y+041591X0180Y0180R090 S3      
317SG               VIA   -    MD0080PA00X+065604Y+041191X0180Y0180R090 S3      
317SG               VIA   -    MD0080PA00X+065604Y+040791X0180Y0180R090 S3      
317SG               VIA   -    MD0080PA00X+065604Y+040391X0180Y0180R090 S3      
317SG               VIA   -    MD0080PA00X+065604Y+039991X0180Y0180R090 S3      
317SG               VIA   -    MD0080PA00X+065604Y+039591X0180Y0180R090 S3      
317SG               VIA   -    MD0080PA00X+065604Y+039191X0180Y0180R090 S3      
317SG               VIA   -    MD0080PA00X+065604Y+038791X0180Y0180R090 S3      
317SG               VIA   -    MD0080PA00X+065604Y+038391X0180Y0180R090 S3      
317SG               VIA   -    MD0080PA00X+065604Y+037991X0180Y0180R090 S3      
317SG               VIA   -    MD0080PA00X+065604Y+037591X0180Y0180R090 S3      
317SG               VIA   -    MD0080PA00X+065604Y+037191X0180Y0180R090 S3      
317SG               VIA   -    MD0080PA00X+065604Y+036791X0180Y0180R090 S3      
317SG               VIA   -    MD0080PA00X+065604Y+036391X0180Y0180R090 S3      
317SG               VIA   -    MD0080PA00X+065604Y+035991X0180Y0180R090 S3      
317SG               VIA   -    MD0080PA00X+065604Y+035591X0180Y0180R090 S3      
317SG               VIA   -    MD0080PA00X+065604Y+035191X0180Y0180R090 S3      
317SG               VIA   -    MD0080PA00X+065604Y+034791X0180Y0180R090 S3      
317SG               VIA   -    MD0080PA00X+065604Y+034391X0180Y0180R090 S3      
317SG               VIA   -    MD0080PA00X+065604Y+033991X0180Y0180R090 S3      
317SG               VIA   -    MD0080PA00X+065604Y+033591X0180Y0180R090 S3      
317SG               VIA   -    MD0080PA00X+065604Y+033191X0180Y0180R090 S3      
317SG               VIA   -    MD0080PA00X+065604Y+032791X0180Y0180R090 S3      
317SG               VIA   -    MD0080PA00X+065604Y+032391X0180Y0180R090 S3      
317SG               VIA   -    MD0080PA00X+065604Y+031991X0180Y0180R090 S3      
317SG               VIA   -    MD0080PA00X+065604Y+031591X0180Y0180R090 S3      
317SG               VIA   -    MD0080PA00X+065604Y+031191X0180Y0180R090 S3      
317SG               VIA   -    MD0080PA00X+065604Y+023558X0180Y0180R259 S3      
327SG               R227  -2          A10X+057720Y+006580X0280Y0240R090 S2      
317SG               VIA   -    MD0100PA00X+051190Y+027620X0200Y0200     S3      
317SG               VIA   -    MD0100PA00X+056334Y+006210X0200Y0200     S3      
317SG               VIA   -    MD0100PA00X+055994Y+006212X0200Y0200     S3      
317SG               VIA   -    MD0100PA00X+024190Y+023880X0200Y0200     S3      
327SG               C68   -2          A10X+024190Y+023550X0280Y0240     S2      
327SG               C71   -2          A10X+027900Y+022060X0280Y0240R270 S2      
327SG               C70   -2          A10X+027900Y+022960X0280Y0240R090 S2      
317SG               VIA   -    MD0100PA00X+028050Y+022430X0200Y0200     S3      
317SG               VIA   -    MD0100PA00X+027526Y+022300X0200Y0200     S3      
327SG               C165  -2          A10X+045551Y+017550X0280Y0240R180 S2      
327SG               U24   -V11        A01X+045609Y+017253X0197Y0197R090 S1      
327SG               C107  -2          A10X+045215Y+018434X0250Y0250R270 S2      
317SG               VIA   -    MD0100PA00X+042780Y+010030X0200Y0200     S3      
327SG               C248  -2          A10X+043200Y+009610X0280Y0240R270 S2      
327SG               C246  -2   M      A10X+042750Y+009610X0280Y0240R270 S2      
327SG               C66   -2          A10X+030410Y+020500X0280Y0240R180 S2      
327SG               C65   -2          A10X+030410Y+020050X0280Y0240R180 S2      
317SG               VIA   -    MD0100PA00X+030897Y+020400X0200Y0200     S3      
327SG               C64   -2          A10X+030680Y+019450X0380Y0540R180 S2      
317SG               VIA   -    MD0100PA00X+024144Y+021500X0200Y0200     S3      
327SG               U10   -3          A10X+024144Y+021930X0130Y0380R180 S2      
317SG               VIA   -    MD0100PA00X+026900Y+021500X0200Y0200     S3      
317SG               VIA   -    MD0100PA00X+058300Y+019200X0200Y0200     S3      
317SG               VIA   -    MD0100PA00X+058050Y+019450X0200Y0200     S3      
327SG               C272  -2          A01X+050890Y+037750X0280Y0240R180 S1      
327SG               C78   -2          A10X+050350Y+038540X0280Y0240R090 S2      
327SG               C73   -2          A10X+050850Y+038540X0280Y0240R090 S2      
317SG               VIA   -    MD0100PA00X+050450Y+037600X0200Y0200     S3      
317SG               VIA   -    MD0100PA00X+050500Y+037950X0200Y0200     S3      
327SG               C72   -2          A01X+050500Y+038370X0380Y0540R270 S1      
327SG               C79   -2          A01X+045880Y+039270X0380Y0540R180 S1      
327SG               C81   -2          A01X+045300Y+038910X0280Y0240R090 S1      
317SG               VIA   -    MD0100PA00X+045400Y+039700X0200Y0200     S3      
317SG               VIA   -    MD0100PA00X+045400Y+039350X0200Y0200     S3      
327SG               C273  -2          A10X+046140Y+039400X0280Y0240     S2      
327SG               C80   -2          A10X+046140Y+038950X0280Y0240     S2      
327SG               R224  -1          A10X+046200Y+024610X0280Y0240R090 S2      
317SG               VIA   -    MD0100PA00X+046200Y+025000X0200Y0200     S3      
327SG               J17   -4          A01X+032374Y+028650X0500Y1400R090 S1      
317SG               VIA   -    MD0100PA00X+033050Y+029150X0200Y0200     S3      
327SG               J17   -2          A01X+032374Y+027650X0500Y1400R090 S1      
317SG               VIA   -    MD0100PA00X+031450Y+027650X0200Y0200     S3      
327SG               U20   -5          A01X+039514Y+028853X0410Y0210R090 S1      
327SG               C274  -2          A01X+060710Y+022250X0280Y0240     S1      
327SG               C275  -2          A01X+060710Y+022700X0280Y0240     S1      
317SG               VIA   -    MD0100PA00X+061050Y+022700X0200Y0200     S3      
327SG               C40   -2          A01X+061410Y+022780X0280Y0240R270 S1      
317SG               VIA   -    MD0100PA00X+061410Y+022410X0200Y0200     S3      
327SG               R99   -2          A10X+025400Y+021740X0280Y0240R090 S2      
317SG               VIA   -    MD0100PA00X+025400Y+021350X0200Y0200     S3      
327SG               C69   -2          A10X+025900Y+022640X0280Y0240R090 S2      
317SG               VIA   -    MD0100PA00X+025900Y+022300X0200Y0200     S3      
327SG               C293  -2          A10X+058250Y+007960X0280Y0240R270 S2      
317SG               VIA   -    MD0100PA00X+058590Y+007960X0200Y0200     S3      
327SG               C231  -2          A01X+057804Y+006090X0120Y0150     S1      
317SG               VIA   -    MD0100PA00X+058064Y+006090X0200Y0200     S3      
327SG               C227  -2          A01X+057720Y+006580X0280Y0240R270 S1      
317SG               VIA   -    MD0100PA00X+058050Y+006580X0200Y0200     S3      
327SG               R233  -1          A10X+054040Y+006900X0280Y0240R180 S2      
317SG               VIA   -    MD0100PA00X+053700Y+006900X0200Y0200     S3      
327SG               C234  -2          A01X+054396Y+006350X0120Y0150R180 S1      
317SG               VIA   -    MD0100PA00X+054396Y+006054X0200Y0200     S3      
327SG               U25   -5          A01X+055653Y+006396X0410Y0210     S1      
327SG               C224  -2          A01X+055750Y+009320X0380Y0540R270 S1      
317SG               VIA   -    MD0100PA00X+063350Y+019687X0200Y0200     S3      
317SG               VIA   -    MD0100PA00X+055900Y+008880X0200Y0200R180 S3      
327SG               C168  -2   M      A10X+049330Y+012630X0380Y0540     S2      
317SG               VIA   -    MD0100PA00X+049330Y+012150X0200Y0200     S3      
327SG               C292  -2   M      A01X+049330Y+012640X0380Y0540R180 S1      
317SG               VIA   -    MD0100PA00X+048940Y+012630X0200Y0200     S3      
317SG               VIA   -    MD0100PA00X+047987Y+013887X0200Y0200     S3      
327SG               R222  -2          A01X+050010Y+014300X0280Y0240     S1      
317SG               VIA   -    MD0100PA00X+050395Y+014300X0200Y0200     S3      
327SG               R216  -2          A10X+044850Y+024610X0280Y0240R270 S2      
327SG               R214  -2          A01X+044400Y+024610X0280Y0240R090 S1      
317SG               VIA   -    MD0100PA00X+044400Y+025000X0200Y0200     S3      
317SG               VIA   -    MD0100PA00X+049650Y+019250X0200Y0200     S3      
317SG               VIA   -    MD0100PA00X+049600Y+020550X0200Y0200     S3      
317SG               VIA   -    MD0100PA00X+053460Y+015200X0200Y0200     S3      
317SG               VIA   -    MD0100PA00X+053460Y+014830X0200Y0200     S3      
327SG               C175  -2          A01X+052975Y+015950X0450Y1040     S1      
327SG               C177  -2          A01X+052975Y+014700X0450Y1040     S1      
327SG               R218  -2          A10X+049260Y+016750X0280Y0240R180 S2      
317SG               VIA   -    MD0100PA00X+049600Y+016750X0200Y0200     S3      
327SG               C159  -2          A10X+040240Y+022150X0280Y0240     S2      
317SG               VIA   -    MD0100PA00X+039900Y+022500X0200Y0200     S3      
327SG               C172  -2          A10X+039825Y+023250X0450Y1040     S2      
317SG               VIA   -    MD0100PA00X+039900Y+022141X0200Y0200     S3      
317SG               VIA   -    MD0100PA00X+037206Y+021300X0200Y0200     S3      
317SG               VIA   -    MD0100PA00X+036956Y+021300X0200Y0200     S3      
327SG               C158  -2          A10X+036780Y+022300X0380Y0540R180 S2      
317SG               VIA   -    MD0100PA00X+047800Y+019800X0200Y0200     S3      
327SG               C103  -2          A10X+047578Y+020009X0250Y0250R180 S2      
327SG               C226  -2          A01X+056400Y+009440X0280Y0240R270 S1      
327SG               R232  -1          A10X+055570Y+007470X0280Y0240R090 S2      
327SG               U25   -11  M      A01X+056250Y+006790X0570Y0710     S0      
317SG               VIA   -    MD0100PA00X+056065Y+007045X0200Y0200     S3      
317SG               VIA   -    MD0100PA00X+056020Y+008150X0200Y0200R180 S3      
317SG               VIA   -    MD0100PA00X+055900Y+008500X0200Y0200R180 S3      
317SG               VIA   -    MD0100PA00X+056250Y+007460X0200Y0200R180 S3      
327SG               C228  -2          A01X+056320Y+008590X0380Y0540R180 S1      
327SG               C230  -2          A01X+056490Y+007920X0280Y0240R180 S1      
327SG               C239  -2          A01X+055500Y+008630X0380Y0540     S1      
327SG               C242  -2          A01X+055690Y+007920X0280Y0240     S1      
317SG               VIA   -    MD0100PA00X+042200Y+007750X0200Y0200     S3      
317SG               VIA   -    MD0100PA00X+043450Y+007700X0200Y0200     S3      
317SG               VIA   -    MD0100PA00X+044843Y+008954X0200Y0200     S3      
317SG               VIA   -    MD0100PA00X+044420Y+010050X0200Y0200     S3      
317SG               VIA   -    MD0100PA00X+043100Y+011650X0200Y0200     S3      
317SG               VIA   -    MD0100PA00X+044140Y+007810X0200Y0200     S3      
327SG               Y3    -3          A01X+044140Y+008237X0350Y0250R090 S1      
327SG               R241  -2          A01X+044600Y+009730X0280Y0240     S1      
317SG               VIA   -    MD0100PA00X+043350Y+010050X0200Y0200     S3      
327SG               R239  -2          A01X+043220Y+009730X0280Y0240R180 S1      
317SG               VIA   -    MD0100PA00X+042300Y+010050X0200Y0200     S3      
317SG               VIA   -    MD0100PA00X+031200Y+029550X0200Y0200     S3      
317SG               VIA   -    MD0100PA00X+029950Y+029550X0200Y0200     S3      
317SG               VIA   -    MD0100PA00X+029200Y+029472X0200Y0200     S3      
317SG               VIA   -    MD0100PA00X+028800Y+029300X0200Y0200     S3      
327SG               C58   -2          A10X+029600Y+029130X0380Y0540R270 S2      
327SG               C282  -2          A10X+030350Y+029130X0380Y0540R270 S2      
327SG               C283  -2          A10X+031100Y+029130X0380Y0540R270 S2      
327SG               C59   -2          A10X+028550Y+028860X0280Y0240R270 S2      
327SG               C60   -2          A10X+029000Y+028860X0280Y0240R270 S2      
317SG               VIA   -    MD0100PA00X+030100Y+031200X0200Y0200R090 S3      
327SG               C180  -2          A10X+036620Y+029520X0380Y0540R090 S2      
317SG               VIA   -    MD0100PA00X+051210Y+024470X0200Y0200     S3      
317SG               VIA   -    MD0100PA00X+051210Y+024070X0200Y0200     S3      
317SG               VIA   -    MD0100PA00X+052980Y+022300X0200Y0200R180 S3      
317SG               VIA   -    MD0100PA00X+053320Y+022000X0200Y0200R180 S3      
317SG               VIA   -    MD0100PA00X+053690Y+020150X0200Y0200R090 S3      
317SG               VIA   -    MD0100PA00X+054350Y+020500X0200Y0200R090 S3      
317SG               VIA   -    MD0100PA00X+054090Y+020150X0200Y0200R090 S3      
317SG               VIA   -    MD0100PA00X+050710Y+024070X0200Y0200     S3      
327SG               U24   -AB9        A01X+047184Y+016466X0197Y0197R090 S1      
317SG               VIA   -    MD0100PA00X+048150Y+018202X0200Y0200     S3      
327SG               C145  -2          A10X+047800Y+018211X0280Y0240R090 S2      
327SG               P1    -15         A01X+027699Y+017912X0100Y0710R270 S1      
327SG               P1    -9          A01X+027699Y+018503X0100Y0710R270 S1      
317SG               VIA   -    MD0100PA00X+044400Y+022600X0200Y0200     S3      
327SG               C223  -2          A10X+044034Y+021978X0250Y0250R270 S2      
327SG               C163  -2   M      A10X+044548Y+022200X0280Y0240     S2      
317SG               VIA   -    MD0100PA00X+036700Y+024124X0200Y0200     S3      
327SG               C51   -2          A01X+036367Y+024124X0120Y0150R090 S1      
317SG               VIA   -    MD0100PA00X+036700Y+023200X0200Y0200     S3      
327SG               C47   -2          A01X+036367Y+023256X0120Y0150R270 S1      
317SG               VIA   -    MD0100PA00X+035498Y+024790X0200Y0200     S3      
317SG               VIA   -    MD0100PA00X+036050Y+024300X0200Y0200     S3      
317SG               VIA   -    MD0100PA00X+035500Y+024250X0200Y0200     S3      
317SG               VIA   -    MD0100PA00X+034150Y+023350X0200Y0200     S3      
327SG               U29   -25         A01X+034515Y+023238X0270Y0100     S1      
317SG               VIA   -    MD0100PA00X+035050Y+022950X0200Y0200     S3      
317SG               VIA   -    MD0100PA00X+034095Y+023700X0200Y0200     S3      
327SG               U29   -2          A01X+034195Y+024050X0100Y0230     S1      
317SG               VIA   -    MD0100PA00X+031160Y+025240X0200Y0200     S3      
317SG               VIA   -    MD0100PA00X+031200Y+023440X0200Y0200     S3      
327SG               R301  -2          A01X+031590Y+023440X0280Y0240R180 S1      
317SG               VIA   -    MD0100PA00X+031200Y+021700X0200Y0200     S3      
327SG               R302  -2          A01X+031590Y+021640X0280Y0240R180 S1      
327SG               P1    -8          A01X+029273Y+018700X0100Y0710R270 S1      
317SG               VIA   -    MD0100PA00X+035120Y+019660X0200Y0200R090 S3      
327SG               U11   -9          A01X+035060Y+019391X0080Y0370R090 S1      
327SG               C162  -2          A10X+042460Y+021584X0250Y0250R270 S2      
327SG               U24   -L22        A01X+042853Y+021584X0197Y0197R090 S1      
327SG               C139  -2   M      A10X+046790Y+018041X0250Y0250R180 S2      
327SG               C154  -2          A10X+046790Y+021584X0250Y0250R270 S2      
327SG               C216  -2          A10X+038916Y+021584X0250Y0250     S2      
327SG               C140  -2          A10X+039310Y+020796X0250Y0250R090 S2      
327SG               C167  -2          A10X+039704Y+019222X0250Y0250     S2      
327SG               C169  -2          A10X+042066Y+014891X0250Y0250R090 S2      
327SG               C208  -2          A10X+042066Y+014497X0250Y0250R270 S2      
327SG               C146  -2          A10X+041278Y+014891X0250Y0250     S2      
327SG               C141  -2          A10X+042460Y+015678X0250Y0250R180 S2      
327SG               C121  -2          A10X+041672Y+015678X0250Y0250R090 S2      
327SG               C142  -2          A10X+043090Y+014847X0250Y0250R270 S2      
327SG               C204  -2          A10X+041278Y+015285X0250Y0250     S2      
327SG               C112  -2          A10X+041672Y+020403X0250Y0250R180 S2      
327SG               C144  -2          A10X+043101Y+019372X0250Y0250R270 S2      
327SG               C149  -2          A10X+043000Y+020290X0280Y0240R270 S2      
327SG               C119  -2          A10X+041672Y+020009X0250Y0250R270 S2      
327SG               C170  -2          A10X+040491Y+019616X0250Y0250R270 S2      
327SG               C153  -2          A10X+040885Y+019615X0250Y0250     S2      
327SG               C221  -2          A10X+042066Y+018828X0250Y0250R270 S2      
327SG               C219  -2          A10X+041990Y+017500X0280Y0240     S2      
327SG               C115  -2          A10X+043060Y+017950X0280Y0240R090 S2      
327SG               C212  -2   M      A10X+043230Y+017410X0280Y0240     S2      
327SG               C113  -2          A10X+040980Y+017500X0280Y0240     S2      
327SG               C200  -2          A10X+042066Y+018041X0250Y0250     S2      
327SG               C109  -2          A10X+042066Y+016860X0250Y0250     S2      
327SG               C156  -2          A10X+041672Y+016860X0250Y0250R270 S2      
327SG               C120  -2          A10X+042066Y+016072X0250Y0250R090 S2      
327SG               C133  -2          A10X+043050Y+015910X0280Y0240R270 S2      
327SG               C114  -2          A10X+043050Y+016490X0280Y0240R090 S2      
327SG               C166  -2          A10X+042460Y+016466X0250Y0250R270 S2      
327SG               C207  -2          A10X+045215Y+016466X0250Y0250R090 S2      
327SG               C210  -2          A10X+046003Y+016860X0250Y0250     S2      
327SG               C151  -2          A10X+046396Y+015678X0250Y0250     S2      
327SG               C93   -2          A10X+046003Y+015678X0250Y0250R270 S2      
327SG               C147  -2          A10X+044822Y+016466X0250Y0250R180 S2      
327SG               C138  -2          A10X+044822Y+016860X0250Y0250R180 S2      
327SG               C128  -2          A10X+044651Y+017550X0280Y0240R180 S2      
327SG               C202  -2          A10X+046396Y+018828X0250Y0250R270 S2      
327SG               C161  -2          A10X+044428Y+016072X0250Y0250R270 S2      
327SG               C201  -2          A10X+044034Y+016466X0250Y0250R090 S2      
327SG               C129  -2          A10X+043641Y+016466X0250Y0250R270 S2      
327SG               C152  -2          A10X+044822Y+015678X0250Y0250R090 S2      
327SG               C160  -2          A10X+045215Y+014104X0250Y0250R270 S2      
327SG               C127  -2          A10X+045609Y+014104X0250Y0250     S2      
327SG               C171  -2          A10X+044034Y+015678X0250Y0250R090 S2      
327SG               C108  -2          A10X+044034Y+013710X0250Y0250R270 S2      
327SG               C135  -2          A10X+044428Y+014104X0250Y0250R090 S2      
327SG               C214  -2          A10X+043641Y+015285X0250Y0250R090 S2      
327SG               C220  -2          A10X+043641Y+014891X0250Y0250R270 S2      
327SG               C132  -2          A10X+044034Y+019222X0250Y0250     S2      
327SG               C134  -2          A10X+044822Y+020796X0250Y0250     S2      
327SG               C260  -2          A01X+053850Y+020570X0380Y0540R270 S1      
327SG               C183  -2          A01X+050560Y+024740X0280Y0240     S1      
327SG               U24   -V1         A01X+045609Y+013316X0197Y0197R090 S1      
327SG               U24   -AA2        A01X+046790Y+013710X0197Y0197R090 S1      
327SG               U24   -U4         A01X+045215Y+014497X0197Y0197R090 S1      
327SG               U24   -P7         A01X+044034Y+015678X0197Y0197R090 S1      
327SG               U24   -P3         A01X+044034Y+014104X0197Y0197R090 S1      
327SG               U24   -N8         A01X+043641Y+016072X0197Y0197R090 S1      
327SG               U24   -N6         A01X+043641Y+015285X0197Y0197R090 S1      
327SG               U24   -N9         A01X+043641Y+016466X0197Y0197R090 S1      
327SG               U24   -M7         A01X+043247Y+015678X0197Y0197R090 S1      
327SG               U24   -M10        A01X+043247Y+016860X0197Y0197R090 S1      
327SG               U24   -M9         A01X+043247Y+016466X0197Y0197R090 S1      
327SG               U24   -L8         A01X+042853Y+016072X0197Y0197R090 S1      
327SG               U24   -L2         A01X+042853Y+013710X0197Y0197R090 S1      
327SG               U24   -L9         A01X+042853Y+016466X0197Y0197R090 S1      
327SG               U24   -L10        A01X+042853Y+016860X0197Y0197R090 S1      
327SG               U24   -K7         A01X+042460Y+015678X0197Y0197R090 S1      
327SG               U24   -K5         A01X+042460Y+014891X0197Y0197R090 S1      
327SG               U24   -K9         A01X+042460Y+016466X0197Y0197R090 S1      
327SG               U24   -J8         A01X+042066Y+016072X0197Y0197R090 S1      
327SG               U24   -H7         A01X+041672Y+015678X0197Y0197R090 S1      
327SG               U24   -H1         A01X+041672Y+013316X0197Y0197R090 S1      
327SG               U24   -G7         A01X+041278Y+015678X0197Y0197R090 S1      
327SG               U24   -G6         A01X+041278Y+015285X0197Y0197R090 S1      
327SG               U24   -G5         A01X+041278Y+014891X0197Y0197R090 S1      
327SG               U24   -F5         A01X+040885Y+014891X0197Y0197R090 S1      
327SG               U24   -E5         A01X+040491Y+014891X0197Y0197R090 S1      
327SG               U24   -E4         A01X+040491Y+014497X0197Y0197R090 S1      
327SG               U24   -D4         A01X+040097Y+014497X0197Y0197R090 S1      
327SG               U24   -D3         A01X+040097Y+014104X0197Y0197R090 S1      
327SG               U24   -C3         A01X+039704Y+014104X0197Y0197R090 S1      
327SG               U24   -A22        A01X+038916Y+021584X0197Y0197R090 S1      
327SG               U24   -B19        A01X+039310Y+020403X0197Y0197R090 S1      
327SG               U24   -C16        A01X+039704Y+019222X0197Y0197R090 S1      
327SG               U24   -G14        A01X+041278Y+018434X0197Y0197R090 S1      
327SG               U24   -D13        A01X+040097Y+018041X0197Y0197R090 S1      
327SG               U24   -J12        A01X+042066Y+017647X0197Y0197R090 S1      
327SG               U24   -G12        A01X+041278Y+017647X0197Y0197R090 S1      
327SG               U24   -D12        A01X+040097Y+017647X0197Y0197R090 S1      
327SG               U24   -A12        A01X+038916Y+017647X0197Y0197R090 S1      
327SG               U24   -C12        A01X+039704Y+017647X0197Y0197R090 S1      
327SG               U24   -B12        A01X+039310Y+017647X0197Y0197R090 S1      
327SG               U24   -K11        A01X+042460Y+017253X0197Y0197R090 S1      
327SG               U24   -H11        A01X+041672Y+017253X0197Y0197R090 S1      
327SG               U24   -F11        A01X+040885Y+017253X0197Y0197R090 S1      
327SG               U24   -E11        A01X+040491Y+017253X0197Y0197R090 S1      
327SG               U24   -A11        A01X+038916Y+017253X0197Y0197R090 S1      
327SG               U24   -J10        A01X+042066Y+016860X0197Y0197R090 S1      
327SG               U24   -G10        A01X+041278Y+016860X0197Y0197R090 S1      
327SG               U24   -C10        A01X+039704Y+016860X0197Y0197R090 S1      
327SG               U24   -A9         A01X+038916Y+016466X0197Y0197R090 S1      
327SG               U24   -H9         A01X+041672Y+016466X0197Y0197R090 S1      
327SG               U24   -G9         A01X+041278Y+016466X0197Y0197R090 S1      
327SG               U24   -E9         A01X+040491Y+016466X0197Y0197R090 S1      
327SG               U24   -G8         A01X+041278Y+016072X0197Y0197R090 S1      
327SG               U24   -D8         A01X+040097Y+016072X0197Y0197R090 S1      
327SG               U24   -A7         A01X+038916Y+015678X0197Y0197R090 S1      
327SG               U24   -E7         A01X+040491Y+015678X0197Y0197R090 S1      
327SG               U24   -C6         A01X+039704Y+015285X0197Y0197R090 S1      
327SG               U24   -A5         A01X+038916Y+014891X0197Y0197R090 S1      
327SG               U24   -A3         A01X+038916Y+014104X0197Y0197R090 S1      
327SG               U24   -B3         A01X+039310Y+014104X0197Y0197R090 S1      
327SG               U24   -A2         A01X+038916Y+013710X0197Y0197R090 S1      
327SG               U24   -AA22       A01X+046790Y+021584X0197Y0197R090 S1      
327SG               U24   -V21        A01X+045609Y+021190X0197Y0197R090 S1      
327SG               U24   -T17        A01X+044822Y+019615X0197Y0197R090 S1      
327SG               U24   -R20        A01X+044428Y+020796X0197Y0197R090 S1      
327SG               U24   -N16        A01X+043641Y+019222X0197Y0197R090 S1      
327SG               U24   -M19        A01X+043247Y+020403X0197Y0197R090 S1      
327SG               U24   -K15        A01X+042460Y+018828X0197Y0197R090 S1      
327SG               U24   -J18        A01X+042066Y+020009X0197Y0197R090 S1      
327SG               U24   -H21        A01X+041672Y+021190X0197Y0197R090 S1      
327SG               U24   -F17        A01X+040885Y+019615X0197Y0197R090 S1      
327SG               U24   -E20        A01X+040491Y+020796X0197Y0197R090 S1      
327SG               U24   -AB19       A01X+047184Y+020403X0197Y0197R090 S1      
327SG               U24   -W18        A01X+046003Y+020009X0197Y0197R090 S1      
327SG               U24   -Y15        A01X+046396Y+018828X0197Y0197R090 S1      
327SG               U24   -U14        A01X+045215Y+018434X0197Y0197R090 S1      
327SG               U24   -P13        A01X+044034Y+018041X0197Y0197R090 S1      
327SG               U24   -AA12       A01X+046790Y+017647X0197Y0197R090 S1      
327SG               U24   -R12        A01X+044428Y+017647X0197Y0197R090 S1      
327SG               U24   -T11        A01X+044822Y+017253X0197Y0197R090 S1      
327SG               U24   -P11        A01X+044034Y+017253X0197Y0197R090 S1      
327SG               U24   -M11        A01X+043247Y+017253X0197Y0197R090 S1      
327SG               U24   -R10        A01X+044428Y+016860X0197Y0197R090 S1      
327SG               U24   -N10        A01X+043641Y+016860X0197Y0197R090 S1      
327SG               U24   -T9         A01X+044822Y+016466X0197Y0197R090 S1      
327SG               U24   -P9         A01X+044034Y+016466X0197Y0197R090 S1      
327SG               U24   -W8         A01X+046003Y+016072X0197Y0197R090 S1      
327SG               U24   -R8         A01X+044428Y+016072X0197Y0197R090 S1      
327SG               U24   -T7         A01X+044822Y+015678X0197Y0197R090 S1      
327SG               U24   -Y5         A01X+046396Y+014891X0197Y0197R090 S1      
317SG               VIA   -    MD0080PA00X+043950Y+033789X0180Y0180     S3      
317SG               VIA   -    MD0080PA00X+044400Y+041650X0180Y0180R270 S3      
327SG               SP2   -1          A10X+033635Y+039470X0050Y0240R180 S0      
317SG               VIA   -    MD0080PA00X+028615Y+032950X0180Y0180     S3      
327SG               C238  -2          A01X+041340Y+029360X0380Y0540R180 S1      
327SG               C240  -2          A01X+041340Y+028550X0380Y0540R180 S1      
327SG               C237  -2          A01X+041450Y+027920X0280Y0240R180 S1      
317SG               VIA   -    MD0100PA00X+032190Y+034300X0200Y0200     S3      
327SG               R155  -1          A10X+032560Y+034300X0280Y0240R180 S2      
327SG               C241  -2          A10X+041340Y+029360X0380Y0540     S2      
327SG               C243  -2          A10X+041340Y+028550X0380Y0540     S2      
327SG               C53   -2          A01X+032870Y+041370X0280Y0240R180 S1      
327SG               C50   -2          A01X+032550Y+042020X0380Y0540R180 S1      
327SG               U6    -3          A01X+033412Y+040661X0450Y0120R270 S1      
327SG               U6    -4          A01X+033195Y+040661X0450Y0120R270 S1      
327SG               U6    -5          A01X+032979Y+040661X0450Y0120R270 S1      
327SG               U6    -8          A01X+032979Y+039579X0450Y0120R270 S1      
327SG               U6    -9          A01X+033195Y+039579X0450Y0120R270 S1      
327SG               U6    -10         A01X+033412Y+039579X0450Y0120R270 S1      
327SG               C52   -2          A01X+033070Y+038870X0280Y0240R180 S1      
327SG               C48   -2          A01X+032850Y+038270X0380Y0540R180 S1      
327SG               C182  -2          A01X+036620Y+029760X0280Y0240R270 S1      
327SG               C188  -2          A01X+037970Y+029690X0280Y0240R270 S1      
327SG               C196  -2          A01X+037970Y+028910X0280Y0240R090 S1      
327SG               C185  -2          A01X+037320Y+029520X0380Y0540R270 S1      
327SG               C194  -2          A01X+037290Y+028700X0380Y0540R090 S1      
327SG               C76   -2          A01X+035940Y+041970X0280Y0240     S1      
317SG               VIA   -    MD0080PA00X+035480Y+028980X0180Y0180R180 S3      
327SG               C199  -2          A01X+035820Y+028980X0280Y0240R090 S1      
317SG               VIA   -    MD0100PA00X+036210Y+029100X0200Y0200R270 S3      
317SG               VIA   -    MD0100PA00X+036580Y+028610X0200Y0200R270 S3      
317SG               VIA   -    MD0100PA00X+036580Y+029110X0200Y0200R270 S3      
317SG               VIA   -    MD0100PA00X+036230Y+028610X0200Y0200R270 S3      
317SG               VIA   -    MD0100PA00X+036150Y+029610X0200Y0200R270 S3      
317SG               VIA   -    MD0100PA00X+032530Y+039170X0200Y0200R090 S3      
317SG               VIA   -    MD0100PA00X+032530Y+039620X0200Y0200R090 S3      
317SG               VIA   -    MD0100PA00X+032480Y+041070X0200Y0200     S3      
317SG               VIA   -    MD0100PA00X+032130Y+041670X0200Y0200     S3      
317SG               VIA   -    MD0100PA00X+032480Y+041520X0200Y0200     S3      
317SG               VIA   -    MD0100PA00X+032130Y+042360X0200Y0200     S3      
317SG               VIA   -    MD0100PA00X+032530Y+038720X0200Y0200R090 S3      
317SG               VIA   -    MD0080PA00X+044650Y+028950X0180Y0180     S3      
317SG               VIA   -    MD0100PA00X+040930Y+028630X0200Y0200R180 S3      
317SG               VIA   -    MD0100PA00X+040910Y+028130X0200Y0200R180 S3      
317SG               VIA   -    MD0100PA00X+040920Y+029170X0200Y0200R180 S3      
317SG               VIA   -    MD0100PA00X+037800Y+027350X0200Y0200R270 S3      
327SG               R189  -1   M      A01X+038160Y+027250X0280Y0240     S1      
317SG               VIA   -    MD0100PA00X+034350Y+025890X0200Y0200     S3      
317SG               VIA   -    MD0080PA00X+035485Y+027610X0180Y0180R180 S3      
327SG               C198  -2          A01X+035820Y+027610X0280Y0240R270 S1      
317SG               VIA   -    MD0100PA00X+032850Y+025890X0200Y0200     S3      
317SG               VIA   -    MD0100PA00X+047750Y+025900X0200Y0200     S3      
317SG               VIA   -    MD0100PA00X+047100Y+025920X0200Y0200     S3      
317SG               VIA   -    MD0100PA00X+049180Y+027770X0200Y0200     S3      
327SG               C191  -2          A01X+049526Y+027770X0120Y0150R180 S1      
317SG               VIA   -    MD0100PA00X+049250Y+027220X0200Y0200     S3      
327SG               C187  -2          A01X+049610Y+027280X0280Y0240R090 S1      
327SG               R174  -2          A10X+049610Y+027280X0280Y0240R270 S2      
317SG               VIA   -    MD0080PA00X+031060Y+033050X0180Y0180R180 S3      
327SG               R154  -1          A10X+030680Y+033050X0280Y0240     S2      
317SG               VIA   -    MD0080PA00X+032220Y+032500X0180Y0180R180 S3      
317SG               VIA   -    MD0100PA00X+039750Y+031290X0200Y0200R270 S3      
327SG               C190  -2          A01X+039820Y+031004X0120Y0150R090 S1      
317SG               VIA   -    MD0100PA00X+039980Y+027840X0200Y0200R270 S3      
327SG               C192  -2          A01X+039624Y+027740X0120Y0150     S1      
317SG               VIA   -    MD0100PA00X+038300Y+029320X0200Y0200R270 S3      
317SG               VIA   -    MD0100PA00X+037800Y+029320X0200Y0200R270 S3      
317SG               VIA   -    MD0100PA00X+037030Y+029110X0200Y0200R270 S3      
317SG               VIA   -    MD0100PA00X+037480Y+029110X0200Y0200R270 S3      
317SG               VIA   -    MD0100PA00X+039330Y+031250X0200Y0200R270 S3      
327SG               R165  -2          A10X+039330Y+030920X0280Y0240R180 S2      
327SG               C184  -2          A01X+039330Y+030920X0280Y0240     S1      
327SG               C46   -2          A01X+035640Y+040320X0280Y0240     S1      
317SG               VIA   -    MD0100PA00X+036000Y+040240X0200Y0200     S3      
327SG               C286  -2          A10X+035640Y+040320X0280Y0240R180 S2      
317SG               VIA   -    MD0100PA00X+036310Y+042280X0200Y0200     S3      
317SG               VIA   -    MD0100PA00X+036031Y+040988X0200Y0200     S3      
327SG               C77   -1          A01X+035474Y+041210X0120Y0150R180 S1      
327SG               R52   -2          A01X+035640Y+040770X0280Y0240     S1      
317SG               VIA   -    MD0100PA00X+036310Y+041830X0200Y0200     S3      
317SG               VIA   -    MD0100PA00X+033800Y+031500X0200Y0200R090 S3      
317SG               VIA   -    MD0080PA00X+044300Y+039650X0180Y0180R270 S3      
327SG               C315  -2          A10X+043960Y+039650X0280Y0240R180 S2      
317SG               VIA   -    MD0080PA00X+044300Y+040150X0180Y0180R270 S3      
327SG               R324  -1          A01X+043960Y+039150X0280Y0240R180 S1      
327SG               C314  -2   M      A01X+043960Y+039650X0280Y0240     S1      
327SG               R323  -2   M      A01X+043960Y+040150X0280Y0240     S1      
317SG               VIA   -    MD0100PA00X+047140Y+036330X0200Y0200     S3      
327SG               P2    -8          A01X+047866Y+036720X0400Y0880R090 S1      
317SG               VIA   -    MD0100PA00X+047100Y+034700X0200Y0200     S3      
327SG               R305  -2          A01X+031590Y+025690X0280Y0240R180 S1      
317SG               ME3   -1   MD1660PA00X+049409Y+041201X2440Y2440     S3      
317SG               ME4   -1   MD1660PA00X+049409Y+030965X2440Y2440     S3      
317SG               VIA   -    MD0100PA00X+038865Y+029265X0200Y0200R090 S3      
327SG               U20   -11  M      A01X+039120Y+029450X0570Y0710R090 S0      
317SG               ME1   -1   MD1660PA00X+025591Y+041201X2440Y2440     S3      
317SG               ME2   -1   MD1660PA00X+025591Y+030965X2440Y2440     S3      
317SG               VIA   -    MD0100PA00X+058150Y+026700X0200Y0200     S3      
327SG               CR7   -1          A10X+057425Y+026375X0570Y0430R270 S2      
317SG               VIA   -    MD0100PA00X+055170Y+025630X0200Y0200     S3      
327SG               J14   -2          A01X+055054Y+026210X0500Y1400R090 S1      
317SG               VIA   -    MD0100PA00X+054900Y+026750X0200Y0200     S3      
327SG               R190  -1          A01X+053280Y+026110X0280Y0240R090 S1      
317SG               VIA   -    MD0100PA00X+053035Y+025748X0200Y0200     S3      
327SG               R188  -1          A10X+052780Y+026110X0280Y0240R270 S2      
317SG               VIA   -    MD0100PA00X+051220Y+025870X0200Y0200     S3      
317SG               VIA   -    MD0100PA00X+051230Y+025440X0200Y0200     S3      
317SG               VIA   -    MD0100PA00X+051210Y+024950X0200Y0200     S3      
317SG               VIA   -    MD0100PA00X+051210Y+026250X0200Y0200     S3      
317SG               VIA   -    MD0100PA00X+054135Y+030351X0200Y0200     S3      
327SG               J14   -10         A01X+055054Y+030210X0500Y1400R090 S1      
317SG               VIA   -    MD0100PA00X+058140Y+029225X0200Y0200     S3      
327SG               CR6   -1          A10X+057375Y+029225X0570Y0430R270 S2      
317SG               VIA   -    MD0100PA00X+052518Y+041192X0200Y0200     S3      
327SG               DS9   -C          A01X+052830Y+041505X0310Y0310R270 S1      
317SG               P3    -6   MD0760PA00X+058878Y+033445X1040Y1040R270 S3      
317SG               P3    -5   MD0760PA00X+058878Y+035098X1040Y1040R270 S3      
317SG               P3    -4   MD0760PA00X+058878Y+036752X1040Y1040R270 S3      
327SG               C197  -2          A01X+051620Y+025920X0280Y0240R180 S1      
327SG               C189  -2          A01X+050840Y+025970X0280Y0240     S1      
327SG               C186  -2          A01X+050800Y+025340X0380Y0540     S1      
327SG               SP3   -1          A10X+056400Y+021655X0050Y0240R270 S0      
327SG               C181  -2          A10X+050800Y+024540X0380Y0540R180 S2      
327SG               C255  -2          A01X+053310Y+022380X0280Y0240R270 S1      
327SG               U26   -3          A01X+055209Y+021432X0450Y0120     S1      
327SG               U26   -4          A01X+055209Y+021215X0450Y0120     S1      
327SG               U26   -5          A01X+055209Y+020999X0450Y0120     S1      
327SG               C261  -2          A01X+054500Y+020890X0280Y0240R270 S1      
327SG               C262  -2          A01X+057000Y+021090X0280Y0240R270 S1      
327SG               U26   -8          A01X+056291Y+020999X0450Y0120     S1      
327SG               U26   -9          A01X+056291Y+021215X0450Y0120     S1      
327SG               U26   -10         A01X+056291Y+021432X0450Y0120     S1      
327SG               J11   -G1         A01X+065158Y+020709X0590Y0750R090 S1      
327SG               J11   -G2         A01X+065158Y+021496X0590Y0750R090 S1      
327SG               C63   -2          A01X+062890Y+019707X0280Y0240R270 S1      
327SG               C61   -2          A01X+062250Y+019707X0380Y0540R270 S1      
327SG               C258  -1          A01X+055100Y+023504X0120Y0150R270 S1      
327SG               C256  -2          A01X+055550Y+023660X0280Y0240R090 S1      
317SG               VIA   -    MD0100PA00X+055380Y+024020X0200Y0200R090 S3      
327SG               R246  -2          A10X+055550Y+023660X0280Y0240R270 S2      
317SG               VIA   -    MD0080PA00X+056660Y+021290X0180Y0180     S3      
317SG               VIA   -    MD0100PA00X+056470Y+020440X0200Y0200R180 S3      
317SG               VIA   -    MD0100PA00X+056870Y+020430X0200Y0200R180 S3      
317SG               VIA   -    MD0100PA00X+057320Y+020430X0200Y0200R180 S3      
317SG               VIA   -    MD0100PA00X+058650Y+023000X0200Y0200R180 S3      
327SG               R297  -2          A01X+058995Y+022840X0280Y0240R180 S1      
317SG               VIA   -    MD0100PA00X+063600Y+021614X0200Y0200     S3      
327SG               C195  -2          A01X+051620Y+025210X0380Y0540R180 S1      
317SG               J11   -GH4 MD0240PA00X+065158Y+022480X0709Y0748R090 S3      
317SG               J11   -GH3 MD0240PA00X+065158Y+019724X0709Y0748R090 S3      
317SG               J11   -GH2 MD0330PA00X+064095Y+022087X0570Y0570R090 S3      
317SG               J11   -GH1 MD0330PA00X+064095Y+020118X0570Y0570R090 S3      
327SG               C279  -2          A01X+035460Y+025130X0280Y0240R270 S1      
327SG               C174  -2          A01X+047400Y+025415X0450Y1040R090 S1      
327SG               R303  -2          A01X+032850Y+025530X0280Y0240R090 S1      
327SG               C280  -2          A01X+033848Y+025530X0280Y0240R090 S1      
327SG               C281  -2   M      A01X+034350Y+025530X0280Y0240R090 S1      
317SG               J1    -GH1 MD0630PA00X+000604Y+013835X0900Y0900     S3      
317SG               J1    -GH2 MD0630PA00X+002604Y+013835X0900Y0900     S3      
317SG               J1    -GH3 MD0630PA00X+000604Y+011835X0900Y0900     S3      
317SG               J1    -GH4 MD0630PA00X+002604Y+011835X0900Y0900     S3      
317SG               J2    -GH1 MD0630PA00X+000604Y+008126X0900Y0900     S3      
317SG               J2    -GH2 MD0630PA00X+002604Y+008126X0900Y0900     S3      
317SG               J2    -GH3 MD0630PA00X+000604Y+006126X0900Y0900     S3      
317SG               J2    -GH4 MD0630PA00X+002604Y+006126X0900Y0900     S3      
317SG               J3    -GH1 MD0630PA00X+000604Y+025252X0900Y0900     S3      
317SG               J3    -GH2 MD0630PA00X+002604Y+025252X0900Y0900     S3      
317SG               J3    -GH3 MD0630PA00X+000604Y+023252X0900Y0900     S3      
317SG               J3    -GH4 MD0630PA00X+002604Y+023252X0900Y0900     S3      
317SG               J4    -GH1 MD0630PA00X+000604Y+019543X0900Y0900     S3      
317SG               J4    -GH2 MD0630PA00X+002604Y+019543X0900Y0900     S3      
317SG               J4    -GH3 MD0630PA00X+000604Y+017543X0900Y0900     S3      
317SG               J4    -GH4 MD0630PA00X+002604Y+017543X0900Y0900     S3      
317SG               MAC_PI-1   MD0790PA00X+012607Y+018404X1000Y1000     S3      
327SG               R402  -2          A10X+054525Y+026795X0280Y0240R270 S2      
327SG               R153  -1          A10X+032560Y+032950X0280Y0240R180 S2      
327SG               R152  -1   M      A10X+032560Y+032500X0280Y0240R180 S2      
327SG               U4    -8          A01X+032815Y+034046X0140Y0620R270 S1      
327SG               C130  -2          A10X+046397Y+019615X0250Y0250R180 S2      
327SG               C215  -2   M      A10X+046397Y+019222X0250Y0250R180 S2      
327SG               C211  -2          A10X+039310Y+020009X0250Y0250     S2      
327SG               C157  -2   M      A10X+039310Y+020403X0250Y0250     S2      
327SG               C285  -2   M      A01X+031590Y+025240X0280Y0240R180 S1      
327SG               R307  -2          A01X+031590Y+024790X0280Y0240R180 S1      
327SG               R212  -2          A01X+049260Y+017200X0280Y0240     S1      
327SG               R288  -1   M      A01X+049260Y+016750X0280Y0240R180 S1      
327SG               R220  -2   M      A10X+044400Y+024610X0280Y0240R270 S2      
327SG               C122  -2          A10X+047667Y+013887X0250Y0250R090 S2      
327SG               U12   -2          A10X+026900Y+021935X0200Y0470R180 S2      
327SG               C62   -2          A10X+032450Y+028590X0280Y0240R090 S2      
327SG               C235  -2   M      A01X+045660Y+028950X0280Y0240     S1      
327SG               C236  -2          A01X+045660Y+029450X0280Y0240     S1      
327SG               C311  -1          A01X+005036Y+010000X0120Y0150     S1      
327SG               U18   -13         A01X+010344Y+035780X0120Y0640     S1      
327SG               R417  -2   M      A10X+064210Y+010800X0280Y0240R180 S2      
327SG               R411  -2          A10X+064210Y+009650X0280Y0240R180 S2      
327SG               R415  -2   M      A10X+064210Y+010200X0280Y0240R180 S2      
327SG               R24   -2          A10X+008890Y+007100X0280Y0240R180 S2      
327SG               R344  -2          A10X+010380Y+007180X0280Y0240     S2      
327SG               R12   -2          A01X+054644Y+039670X0280Y0240R180 S1      
327SG               R5    -2          A01X+057620Y+035170X0280Y0240     S1      
327SG               C3    -2   M      A01X+057620Y+035670X0280Y0240     S1      
327SG               U31   -5          A10X+017485Y+033880X0200Y0650R270 S2      
327SG               R69   -2          A10X+059690Y+019086X0280Y0240R090 S2      
327SG               U33   -4          A01X+042391Y+039920X0490Y0120R180 S1      
327SG               R16   -2          A10X+057620Y+039070X0280Y0240R180 S2      
327SG               R10   -2   M      A10X+057620Y+038570X0280Y0240R180 S2      
327m0291            U27   -1          A01X+059605Y+020442X0410Y0120R090 S1      
317m0291            VIA   -    MD0080PA00X+059190Y+020030X0180Y0180R180 S3      
327m0291            R66   -2          A01X+059190Y+019506X0280Y0240R090 S1      
327m0292            U27   -4          A01X+060195Y+020442X0410Y0120R090 S1      
317m0292            VIA   -    MD0080PA00X+060690Y+020040X0180Y0180R180 S3      
327m0292            R67   -2          A01X+060690Y+019506X0280Y0240R090 S1      
327R_MAC_USB_DP     R97   -1          A01X+031190Y+018950X0280Y0240     S1      
327R_MAC_USB_DP     P1    -2          A01X+029273Y+019290X0100Y0710R270 S1      
327R_MAC_USB_DM     R98   -1          A01X+031190Y+018500X0280Y0240     S1      
327R_MAC_USB_DM     P1    -4          A01X+029273Y+019093X0100Y0710R270 S1      
317m0293            VIA   -    MD0080PA00X+034900Y+008250X0180Y0180R090 S3      
317m0293            MAC_PI-1    D0790PA00X+026597Y+009344X1000Y1000     S3      
327m0293            R82   -1          A10X+060360Y+027900X0280Y0240     S2      
317m0293            VIA   -    MD0100PA00X+060950Y+025450X0200Y0200     S3      
327m0293            R94   -1          A01X+049260Y+019750X0280Y0240R180 S1      
317m0293            VIA   -    MD0100PA00X+050700Y+018850X0200Y0200     S3      
317m0293            VIA   -    MD0080PA00X+053300Y+009950X0180Y0180     S3      
317m0294            VIA   -    MD0100PA00X+035400Y+008250X0200Y0200     S3      
317m0294            VIA   -    MD0100PA00X+060400Y+025450X0200Y0200     S3      
327m0294            R81   -1          A10X+060360Y+026150X0280Y0240     S2      
327m0294            R95   -1          A01X+049260Y+020250X0280Y0240R180 S1      
317m0294            VIA   -    MD0100PA00X+050700Y+019250X0200Y0200     S3      
327m0294            R264  -2          A10X+049260Y+020250X0280Y0240R180 S2      
317m0294            VIA   -    MD0080PA00X+053300Y+009500X0180Y0180     S3      
317m0294            MAC_PI-1    D0790PA00X+025397Y+009344X1000Y1000     S3      
327R_MAC_PPS_OUTP   R87   -2          A01X+031230Y+018000X0280Y0240R180 S1      
327R_MAC_PPS_OUTP   P1    -17         A01X+027699Y+017715X0100Y0710R270 S1      
327R_MAC_PPS_OUTN   R88   -2          A01X+031230Y+017500X0280Y0240R180 S1      
327R_MAC_PPS_OUTN   P1    -19         A01X+027699Y+017518X0100Y0710R270 S1      
327R_MAC_PPS_IN1P   R89   -1          A10X+027965Y+019450X0280Y0240R180 S2      
317R_MAC_PPS_IN1P   VIA   -    MD0080PA00X+028020Y+019870X0180Y0180     S3      
327R_MAC_PPS_IN1P   R83   -2          A01X+031680Y+021100X0280Y0240R180 S1      
327R_MAC_PPS_IN1P   P1    -1          A01X+027699Y+019290X0100Y0710R270 S1      
327R_MAC_PPS_IN1N   R89   -2          A10X+028385Y+019450X0280Y0240R180 S2      
317R_MAC_PPS_IN1N   VIA   -    MD0080PA00X+028340Y+019870X0180Y0180     S3      
327R_MAC_PPS_IN1N   R84   -2          A01X+031680Y+020600X0280Y0240R180 S1      
327R_MAC_PPS_IN1N   P1    -3          A01X+027699Y+019093X0100Y0710R270 S1      
327R_MAC_PPS_IN0P   R90   -2          A10X+027950Y+018800X0280Y0240R270 S2      
317R_MAC_PPS_IN0P   VIA   -    MD0080PA00X+028450Y+018750X0180Y0180     S3      
327R_MAC_PPS_IN0P   P1    -5          A01X+027699Y+018896X0100Y0710R270 S1      
327R_MAC_PPS_IN0P   R85   -2          A01X+031680Y+020150X0280Y0240R180 S1      
327R_MAC_PPS_IN0N   R90   -1          A10X+027950Y+018380X0280Y0240R270 S2      
317R_MAC_PPS_IN0N   VIA   -    MD0080PA00X+028450Y+018430X0180Y0180     S3      
327R_MAC_PPS_IN0N   P1    -7          A01X+027699Y+018700X0100Y0710R270 S1      
327R_MAC_PPS_IN0N   R86   -2          A01X+031680Y+019650X0280Y0240R180 S1      
317R_MAC_BITEOUT    MAC_PI-1    D0790PA00X+027787Y+009344X1000Y1000     S3      
317R_MAC_BITEOUT    TP62  -1   MD0100PA00X+049700Y+015400X0200Y0200     S2      
327R_MAC_BITEOUT    R93   -1          A01X+049260Y+016300X0280Y0240R180 S1      
327m0295            R92   -1          A10X+049260Y+018550X0280Y0240     S2      
317m0295            VIA   -    MD0100PA00X+049806Y+018550X0200Y0200     S3      
317m0295            MAC_PI-1    D0790PA00X+012607Y+010404X1000Y1000     S3      
317m0296            VIA   -    MD0100PA00X+007240Y+026460X0200Y0200     S3      
327m0296            R72   -2          A01X+006845Y+026640X0280Y0240     S1      
327m0296            U28   -4          A01X+007590Y+026610X0140Y0110R180 S1      
317m0297            VIA   -    MD0080PA00X+007580Y+027430X0180Y0180     S3      
327m0297            R73   -2          A01X+007140Y+027900X0280Y0240R180 S1      
327m0297            U28   -2          A01X+007796Y+026915X0110Y0140R180 S1      
317R_BNO080_RST_N   TP16  -1    D0100PA00X+032350Y+026300X0200Y0200     S2      
317R_BNO080_RST_N   VIA   -    MD0080PA00X+032750Y+023200X0180Y0180     S3      
327R_BNO080_RST_N   R291  -2          A01X+032010Y+023890X0280Y0240     S1      
327R_BNO080_RST_N   R78   -1   M      A01X+032010Y+022990X0280Y0240R180 S1      
327R_BNO080_RST_N   R301  -1   M      A01X+032010Y+023440X0280Y0240R180 S1      
327R_BNO080_RST_N   U29   -11         A01X+033285Y+023042X0270Y0100     S1      
317R_BNO080_INT_N   VIA   -    MD0100PA00X+032400Y+022750X0200Y0200     S3      
327R_BNO080_INT_N   R79   -2          A01X+032010Y+022540X0280Y0240     S1      
327R_BNO080_INT_N   U29   -14         A01X+033285Y+022451X0270Y0100     S1      
317R_BNO080_INT_N   TP17  -1    D0100PA00X+033050Y+026500X0200Y0200     S2      
317m0298            TP18  -1    D0100PA00X+033750Y+026500X0200Y0200     S2      
317m0298            VIA   -    MD0080PA00X+033260Y+024660X0180Y0180     S3      
327m0298            R80   -2          A10X+033350Y+025110X0280Y0240R090 S2      
327m0298            R304  -2          A01X+033350Y+025110X0280Y0240R270 S1      
327m0298            U29   -4          A01X+033802Y+024050X0100Y0230     S1      
317PCIE_CONN_TMS    VIA   -    MD0080PA00X+021481Y+007881X0180Y0180     S3      
317PCIE_CONN_TMS    VIA   -    MD0100PA00X+050800Y+011050X0200Y0200     S3      
327PCIE_CONN_TMS    R43   -1          A10X+054540Y+028700X0280Y0240R180 S2      
327PCIE_CONN_TMS    VIA   -    M      A10X+020830Y+005250X0300Y0300     S2      
327PCIE_CONN_TMS    GF1   -A8         A10X+020728Y+001378X0280Y1650     S2      
317PCIE_CONN_TDO    VIA   -    MD0100PA00X+052250Y+011450X0200Y0200     S3      
327PCIE_CONN_TDO    R42   -1          A10X+055460Y+028150X0280Y0240     S2      
317PCIE_CONN_TDO    VIA   -    MD0100PA00X+051320Y+006600X0200Y0200     S3      
317PCIE_CONN_TDO    VIA   -    MD0100PA00X+020816Y+007399X0200Y0200     S3      
327PCIE_CONN_TDO    GF1   -A7         A10X+020335Y+001378X0280Y1650     S2      
327PCIE_CONN_TDO    VIA   -    M      A10X+020137Y+004300X0300Y0300     S2      
327PCIE_CONN_TDI    VIA   -    M      A10X+019800Y+004950X0300Y0300     S2      
327PCIE_CONN_TDI    GF1   -A6         A10X+019941Y+001378X0280Y1650     S2      
317PCIE_CONN_TDI    VIA   -    MD0080PA00X+020300Y+007500X0180Y0180     S3      
317PCIE_CONN_TDI    VIA   -    MD0100PA00X+050800Y+011550X0200Y0200     S3      
327PCIE_CONN_TDI    R41   -1          A10X+055460Y+030650X0280Y0240     S2      
317PCIE_CONN_TCK    VIA   -    MD0100PA00X+050800Y+010550X0200Y0200     S3      
327PCIE_CONN_TCK    R28   -1          A10X+055460Y+025950X0280Y0240     S2      
317PCIE_CONN_TCK    VIA   -    MD0080PA00X+020788Y+007874X0180Y0180     S3      
327PCIE_CONN_TCK    VIA   -    M      A10X+019240Y+004579X0300Y0300     S2      
327PCIE_CONN_TCK    GF1   -A5         A10X+019547Y+001378X0280Y1650     S2      
327m0299            GF1   -A11        A10X+021909Y+001378X0280Y1650     S2      
317m0299            TP48  -1   MD0100PA00X+022958Y+004892X0200Y0200     S2      
317m0299            VIA   -    MD0080PA00X+026330Y+005220X0180Y0180     S3      
327m0299            R55   -1          A01X+026370Y+006550X0280Y0240R180 S1      
327m0299            U3    -2          A01X+027540Y+006050X0130Y0380R090 S1      
327m0299            R56   -2   M      A01X+026370Y+006050X0280Y0240     S1      
317m0300            VIA   -    MD0100PA00X+034550Y+008700X0200Y0200     S3      
317m0300            VIA   -    MD0100PA00X+009225Y+009775X0200Y0200     S3      
317m0300            VIA   -    MD0100PA00X+048200Y+008350X0200Y0200     S3      
327m0300            U37   -4          A01X+048855Y+008428X0140Y0620R090 S1      
327m0300            R144  -1          A10X+006760Y+015990X0280Y0240R180 S2      
317m0300            VIA   -    MD0100PA00X+008825Y+017725X0200Y0200     S3      
317m0301            VIA   -    MD0100PA00X+034050Y+008700X0200Y0200     S3      
317m0301            VIA   -    MD0100PA00X+009650Y+009800X0200Y0200     S3      
317m0301            VIA   -    MD0100PA00X+009100Y+018150X0200Y0200     S3      
327m0301            R145  -1          A10X+006750Y+015440X0280Y0240R180 S2      
317m0301            VIA   -    MD0100PA00X+047800Y+007800X0200Y0200     S3      
327m0301            U37   -7          A01X+048855Y+007660X0140Y0620R090 S1      
327MAC_USB_DP       R436  -2          A10X+044428Y+018434X0250Y0250R270 S2      
317MAC_USB_DP       VIA   -    MD0080PA00X+044231Y+018631X0180Y0180     S0      
327MAC_USB_DP       U24   -P14        A01X+044034Y+018434X0197Y0197R090 S1      
327MAC_USB_DP       R106  -2          A10X+035750Y+018865X0280Y0240R180 S2      
327MAC_USB_DP       U11   -3          A01X+035821Y+018919X0080Y0370R090 S1      
317MAC_USB_DP       VIA   -    MD0080PA00X+036510Y+018836X0180Y0180R180 S3      
327MAC_USB_DM       R437  -2          A10X+044822Y+018434X0250Y0250R270 S2      
317MAC_USB_DM       VIA   -    MD0080PA00X+044625Y+018631X0180Y0180     S0      
327MAC_USB_DM       U24   -R14        A01X+044428Y+018434X0197Y0197R090 S1      
327MAC_USB_DM       U11   -4          A01X+035821Y+019076X0080Y0370R090 S1      
327MAC_USB_DM       R105  -2          A10X+035750Y+019315X0280Y0240R180 S2      
317MAC_USB_DM       VIA   -    MD0080PA00X+036510Y+019156X0180Y0180R180 S3      
327MAC_ALARM        R96   -1          A01X+031240Y+016950X0280Y0240     S1      
317MAC_ALARM        TP51  -1   MD0100PA00X+030650Y+016950X0200Y0200     S2      
317MAC_ALARM        VIA   -    MD0100PA00X+029828Y+017518X0200Y0200     S3      
327MAC_ALARM        P1    -20         A01X+029273Y+017518X0100Y0710R270 S1      
317LM75B_I2C_SDA    VIA   -    MD0100PA00X+022250Y+032450X0200Y0200     S3      
327LM75B_I2C_SDA    R406  -1   M      A01X+022628Y+032450X0280Y0240R090 S1      
327LM75B_I2C_SDA    U4    -4          A01X+032815Y+033022X0140Y0620R270 S1      
317LM75B_I2C_SDA    VIA   -    MD0100PA00X+045950Y+026200X0200Y0200     S3      
317LM75B_I2C_SDA    VIA   -    MD0100PA00X+040250Y+030800X0200Y0200     S3      
317LM75B_I2C_SDA    VIA   -    MD0100PA00X+006200Y+030700X0200Y0200     S3      
327LM75B_I2C_SDA    R332  -1   M      A10X+006600Y+030560X0280Y0240R090 S2      
317LM75B_I2C_SDA    VIA   -    MD0100PA00X+058650Y+011250X0200Y0200     S3      
327LM75B_I2C_SDA    R20   -2   M      A01X+059140Y+011250X0280Y0240R180 S1      
327LM75B_I2C_SDA    R407  -1          A01X+059140Y+010800X0280Y0240     S1      
327LM75B_I2C_SCL    U36   -2          A01X+060845Y+010578X0180Y0600R090 S1      
317LM75B_I2C_SCL    VIA   -    MD0100PA00X+058650Y+010700X0200Y0200     S3      
327LM75B_I2C_SCL    U35   -2          A01X+021478Y+032655X0180Y0600     S1      
317LM75B_I2C_SCL    VIA   -    MD0100PA00X+022650Y+033400X0200Y0200     S3      
327LM75B_I2C_SCL    U4    -5          A01X+032815Y+033278X0140Y0620R270 S1      
317LM75B_I2C_SCL    VIA   -    MD0100PA00X+045700Y+025850X0200Y0200     S3      
317LM75B_I2C_SCL    VIA   -    MD0100PA00X+040200Y+030300X0200Y0200     S3      
317LM75B_I2C_SCL    VIA   -    MD0100PA00X+006450Y+029675X0200Y0200     S3      
327LM75B_I2C_SCL    U8    -2          A10X+005505Y+030028X0180Y0600R270 S2      
327LM75B_I2C_SCL    R21   -2   M      A01X+059560Y+010250X0280Y0240     S1      
317LED_DATOUT3      VIA   -    MD0100PA00X+054883Y+041633X0200Y0200     S3      
327LED_DATOUT3      DS1   -C          A01X+054350Y+042165X0310Y0310R270 S1      
327LED_DATOUT3      U24   -D15        A01X+040097Y+018828X0197Y0197R090 S1      
317LED_DATOUT3      VIA   -    MD0080PA00X+039900Y+019025X0180Y0180     S0      
317LED_DATOUT2      VIA   -    MD0100PA00X+055532Y+041750X0200Y0200     S3      
327LED_DATOUT2      DS2   -C          A01X+055532Y+042165X0310Y0310R270 S1      
317LED_DATOUT2      VIA   -    MD0080PA00X+039900Y+018631X0180Y0180     S0      
327LED_DATOUT2      U24   -D14        A01X+040097Y+018434X0197Y0197R090 S1      
317LED_DATOUT1      VIA   -    MD0100PA00X+056713Y+041750X0200Y0200     S3      
327LED_DATOUT1      DS3   -C          A01X+056713Y+042165X0310Y0310R270 S1      
317LED_DATOUT1      VIA   -    MD0080PA00X+039507Y+018237X0180Y0180     S0      
327LED_DATOUT1      U24   -C13        A01X+039704Y+018041X0197Y0197R090 S1      
317LED_DATOUT0      VIA   -    MD0100PA00X+057894Y+041750X0200Y0200     S3      
327LED_DATOUT0      DS4   -C          A01X+057894Y+042165X0310Y0310R270 S1      
317LED_DATOUT0      VIA   -    MD0080PA00X+039113Y+018237X0180Y0180     S0      
327LED_DATOUT0      U24   -B13        A01X+039310Y+018041X0197Y0197R090 S1      
317IO_L24P_16       TP187 -1    D0100PA00X+042050Y+022950X0200Y0200     S2      
327IO_L24P_16       U24   -G21        A01X+041278Y+021190X0197Y0197R090 S1      
317IO_L24N_34       TP141 -1    D0100PA00X+046593Y+016269X0200Y0200     S2      
327IO_L24N_34       U24   -Y9         A01X+046396Y+016466X0197Y0197R090 S1      
317IO_L24N_16       TP188 -1    D0100PA00X+042540Y+022960X0200Y0200     S2      
327IO_L24N_16       U24   -G22        A01X+041278Y+021584X0197Y0197R090 S1      
317IO_L23P_16       TP185 -1    D0100PA00X+042300Y+023540X0200Y0200     S2      
327IO_L23P_16       U24   -E21        A01X+040491Y+021190X0197Y0197R090 S1      
317IO_L23N_34       TP139 -1    D0100PA00X+049150Y+014850X0200Y0200     S2      
317IO_L23N_34       VIA   -    MD0080PA00X+046593Y+015482X0180Y0180     S0      
327IO_L23N_34       U24   -Y7         A01X+046396Y+015678X0197Y0197R090 S1      
317IO_L23N_16       TP186 -1    D0100PA00X+039400Y+022350X0200Y0200     S2      
327IO_L23N_16       U24   -D21        A01X+040097Y+021190X0197Y0197R090 S1      
317IO_L22P_34       TP136 -1    D0100PA00X+048500Y+015400X0200Y0200     S2      
327IO_L22P_34       U24   -AA8        A01X+046790Y+016072X0197Y0197R090 S1      
317IO_L22P_16       TP183 -1    D0100PA00X+041490Y+022980X0200Y0200     S2      
327IO_L22P_16       U24   -E22        A01X+040491Y+021584X0197Y0197R090 S1      
317IO_L22N_16       TP184 -1    D0100PA00X+041610Y+023540X0200Y0200     S2      
327IO_L22N_16       U24   -D22        A01X+040097Y+021584X0197Y0197R090 S1      
317IO_L21P_16       TP181 -1    D0100PA00X+037500Y+021000X0200Y0200     S2      
327IO_L21P_16       U24   -B21        A01X+039310Y+021190X0197Y0197R090 S1      
317IO_L21N_34       TP135 -1    D0100PA00X+049750Y+014850X0200Y0200     S2      
317IO_L21N_34       VIA   -    MD0080PA00X+045806Y+015875X0180Y0180     S0      
327IO_L21N_34       U24   -V8         A01X+045609Y+016072X0197Y0197R090 S1      
317IO_L21N_16       TP182 -1    D0100PA00X+038000Y+021000X0200Y0200     S2      
327IO_L21N_16       U24   -A21        A01X+038916Y+021190X0197Y0197R090 S1      
317IO_L20P_34       TP132 -1    D0100PA00X+047381Y+015482X0200Y0200R090 S2      
327IO_L20P_34       U24   -AB7        A01X+047184Y+015678X0197Y0197R090 S1      
317IO_L20P_16       TP78  -1    D0100PA00X+039000Y+023250X0200Y0200R090 S2      
327IO_L20P_16       U24   -C22        A01X+039704Y+021584X0197Y0197R090 S1      
317IO_L20N_34       TP133 -1    D0100PA00X+047381Y+015088X0200Y0200     S2      
327IO_L20N_34       U24   -AB6        A01X+047184Y+015285X0197Y0197R090 S1      
317IO_L20N_16       TP180 -1    D0100PA00X+038300Y+023250X0200Y0200R090 S2      
327IO_L20N_16       U24   -B22        A01X+039310Y+021584X0197Y0197R090 S1      
327m0302            U32   -6          A01X+008338Y+024275X0180Y0600R180 S1      
317m0302            VIA   -    MD0080PA00X+008460Y+024890X0180Y0180     S3      
327m0302            R316  -1          A10X+008050Y+024440X0280Y0240R090 S2      
317m0302            VIA   -    MD0100PA00X+032800Y+030650X0200Y0200     S3      
327m0302            R281  -2   M      A10X+008500Y+024440X0280Y0240R270 S2      
327m0302            U4    -9          A01X+030425Y+034046X0140Y0620R270 S1      
327m0303            U32   -7          A01X+008082Y+024275X0180Y0600R180 S1      
317m0303            VIA   -    MD0080PA00X+007960Y+024890X0180Y0180     S3      
317m0303            VIA   -    MD0100PA00X+033250Y+030650X0200Y0200     S3      
327m0303            R315  -1   M      A10X+007600Y+024440X0280Y0240R090 S2      
327m0303            R282  -2          A10X+007150Y+024440X0280Y0240R270 S2      
327m0303            U4    -10         A01X+030425Y+033790X0140Y0620R270 S1      
327GPS_UART_TXD     R109  -2          A10X+049850Y+035460X0280Y0240R270 S2      
327GPS_UART_TXD     R112  -2          A01X+049850Y+035460X0280Y0240R090 S1      
317GPS_UART_TXD     VIA   -    MD0080PA00X+050300Y+035460X0180Y0180     S3      
327GPS_UART_TXD     P2    -3          A01X+049155Y+038295X0400Y0880R090 S1      
327GPS_UART_RXD     R110  -2          A10X+049350Y+035460X0280Y0240R270 S2      
327GPS_UART_RXD     R268  -2   M      A01X+049350Y+035460X0280Y0240R090 S1      
327GPS_UART_RXD     R113  -2          A01X+048850Y+035460X0280Y0240R090 S1      
317GPS_UART_RXD     VIA   -    MD0080PA00X+049350Y+035900X0180Y0180     S3      
327GPS_UART_RXD     P2    -5          A01X+049155Y+037508X0400Y0880R090 S1      
327GPS_RST_N        R116  -1          A01X+047850Y+035460X0280Y0240R270 S1      
327GPS_RST_N        R114  -1   M      A01X+047350Y+035460X0280Y0240R270 S1      
317GPS_RST_N        TP15  -1   MD0100PA00X+046700Y+035550X0200Y0200     S2      
327GPS_RST_N        R115  -2          A10X+047360Y+035510X0280Y0240     S2      
327GPS_RST_N        P2    -4          A01X+047866Y+038295X0400Y0880R090 S1      
327GPSTP2_OUT       R111  -2          A10X+048850Y+035460X0280Y0240R270 S2      
317GPSTP2_OUT       VIA   -    MD0080PA00X+048850Y+035900X0180Y0180     S3      
327GPSTP2_OUT       P2    -7          A01X+049155Y+036720X0400Y0880R090 S1      
327GPSTP1_OUT       R117  -1          A01X+048350Y+035460X0280Y0240R270 S1      
317GPSTP1_OUT       VIA   -    MD0080PA00X+047046Y+036946X0180Y0180     S3      
327GPSTP1_OUT       P2    -6          A01X+047866Y+037508X0400Y0880R090 S1      
317FPGA_TMS         VIA   -    MD0080PA00X+045018Y+018237X0180Y0180     S0      
317FPGA_TMS         VIA   -    MD0100PA00X+053950Y+029200X0200Y0200     S3      
327FPGA_TMS         U24   -T13        A01X+044822Y+018041X0197Y0197R090 S1      
327FPGA_TMS         R43   -2          A10X+054960Y+028700X0280Y0240R180 S2      
327FPGA_TMS         R136  -2   M      A10X+055020Y+029225X0280Y0240     S2      
327FPGA_TMS         R404  -2   M      A10X+054520Y+029225X0280Y0240R090 S2      
327FPGA_TDO         R42   -2          A10X+055040Y+028150X0280Y0240     S2      
327FPGA_TDO         R195  -1          A10X+049260Y+018100X0280Y0240     S2      
317FPGA_TDO         VIA   -    MD0100PA00X+050150Y+019250X0200Y0200     S3      
327FPGA_TDO         R403  -2   M      A10X+054520Y+027710X0280Y0240R090 S2      
327FPGA_TDO         R135  -2   M      A10X+055040Y+027700X0280Y0240     S2      
317FPGA_TDO         VIA   -    MD0080PA00X+053998Y+027512X0180Y0180     S3      
327FPGA_TDI         R41   -2          A10X+055040Y+030650X0280Y0240     S2      
317FPGA_TDI         VIA   -    MD0080PA00X+044625Y+018237X0180Y0180     S0      
327FPGA_TDI         R137  -2   M      A10X+055040Y+030200X0280Y0240     S2      
327FPGA_TDI         R405  -2   M      A10X+054520Y+030190X0280Y0240R090 S2      
317FPGA_TDI         VIA   -    MD0080PA00X+053750Y+029661X0180Y0180     S3      
327FPGA_TDI         U24   -R13        A01X+044428Y+018041X0197Y0197R090 S1      
327FPGA_TCK         R28   -2          A10X+055040Y+025950X0280Y0240     S2      
317FPGA_TCK         VIA   -    MD0080PA00X+045806Y+017844X0180Y0180     S0      
327FPGA_TCK         R402  -1   M      A10X+054525Y+026375X0280Y0240R270 S2      
327FPGA_TCK         R134  -2   M      A10X+055040Y+026400X0280Y0240     S2      
317FPGA_TCK         VIA   -    MD0080PA00X+054525Y+025630X0180Y0180     S3      
327FPGA_TCK         U24   -V12        A01X+045609Y+017647X0197Y0197R090 S1      
317EEPROM_I2C_SDA   VIA   -    MD0100PA00X+035450Y+006092X0200Y0200     S3      
327EEPROM_I2C_SDA   U37   -9          A01X+051245Y+007404X0140Y0620R090 S1      
317EEPROM_I2C_SDA   VIA   -    MD0080PA00X+013950Y+006250X0180Y0180     S3      
317EEPROM_I2C_SDA   VIA   -    MD0100PA00X+050850Y+006450X0200Y0200     S3      
327EEPROM_I2C_SDA   R183  -1          A01X+013505Y+006130X0280Y0240R180 S1      
317EEPROM_I2C_SCL   VIA   -    MD0100PA00X+034950Y+006100X0200Y0200     S3      
327EEPROM_I2C_SCL   U37   -12         A01X+051245Y+008172X0140Y0620R090 S1      
317EEPROM_I2C_SCL   VIA   -    MD0100PA00X+050400Y+006450X0200Y0200     S3      
317EEPROM_I2C_SCL   VIA   -    MD0080PA00X+014850Y+006250X0180Y0180     S3      
327EEPROM_I2C_SCL   R184  -1          A01X+013507Y+007080X0280Y0240R180 S1      
327C_PCIEREFCLKP    GF1   -A13        A10X+023484Y+001378X0280Y1650     S2      
327C_PCIEREFCLKP    C19   -1          A10X+023431Y+005839X0280Y0240R270 S2      
327C_PCIEREFCLKN    GF1   -A14        A10X+023878Y+001378X0280Y1650     S2      
327C_PCIEREFCLKN    C23   -1          A10X+023931Y+005840X0280Y0240R270 S2      
327m0304            C35   -1          A10X+029730Y+005840X0280Y0240R270 S2      
327m0304            GF1   -A29        A10X+029783Y+001378X0280Y1650     S2      
327m0305            C36   -1          A10X+030230Y+005840X0280Y0240R270 S2      
327m0305            GF1   -A30        A10X+030177Y+001378X0280Y1650     S2      
327m0306            C28   -1          A10X+028006Y+005840X0280Y0240R270 S2      
327m0306            GF1   -A25        A10X+028209Y+001378X0280Y1650     S2      
327m0307            C34   -1          A10X+028506Y+005840X0280Y0240R270 S2      
327m0307            GF1   -A26        A10X+028602Y+001378X0280Y1650     S2      
327m0308            C26   -1          A10X+026581Y+005840X0280Y0240R270 S2      
327m0308            GF1   -A21        A10X+026634Y+001378X0280Y1650     S2      
327m0309            C27   -1          A10X+027081Y+005840X0280Y0240R270 S2      
327m0309            GF1   -A22        A10X+027028Y+001378X0280Y1650     S2      
327m0310            C24   -1          A10X+024612Y+005840X0280Y0240R270 S2      
327m0310            GF1   -A16        A10X+024665Y+001378X0280Y1650     S2      
327m0311            C25   -1          A10X+025112Y+005840X0280Y0240R270 S2      
327m0311            GF1   -A17        A10X+025059Y+001378X0280Y1650     S2      
317m0312            VIA   -    MD0080PA00X+039900Y+016269X0180Y0180     S0      
327m0312            U24   -D9         A01X+040097Y+016466X0197Y0197R090 S1      
317m0312            VIA   -    MD0080PA00X+029584Y+003850X0180Y0180     S3      
327m0312            GF1   -B27        A01X+028996Y+001378X0280Y1650     S1      
317m0313            VIA   -    MD0080PA00X+039507Y+016269X0180Y0180     S0      
327m0313            U24   -C9         A01X+039704Y+016466X0197Y0197R090 S1      
317m0313            VIA   -    MD0080PA00X+029584Y+003530X0180Y0180     S3      
327m0313            GF1   -B28        A01X+029390Y+001378X0280Y1650     S1      
317m0314            VIA   -    MD0080PA00X+039113Y+016663X0180Y0180     S0      
327m0314            U24   -B10        A01X+039310Y+016860X0197Y0197R090 S1      
317m0314            VIA   -    MD0080PA00X+028009Y+003850X0180Y0180     S3      
327m0314            GF1   -B23        A01X+027421Y+001378X0280Y1650     S1      
317m0315            VIA   -    MD0080PA00X+038719Y+016663X0180Y0180     S0      
327m0315            U24   -A10        A01X+038916Y+016860X0197Y0197R090 S1      
317m0315            VIA   -    MD0080PA00X+028009Y+003530X0180Y0180     S3      
327m0315            GF1   -B24        A01X+027815Y+001378X0280Y1650     S1      
317m0316            VIA   -    MD0080PA00X+039900Y+017056X0180Y0180     S0      
327m0316            U24   -D11        A01X+040097Y+017253X0197Y0197R090 S1      
317m0316            VIA   -    MD0080PA00X+026434Y+003850X0180Y0180     S3      
327m0316            GF1   -B19        A01X+025846Y+001378X0280Y1650     S1      
317m0317            VIA   -    MD0080PA00X+039507Y+017056X0180Y0180     S0      
327m0317            U24   -C11        A01X+039704Y+017253X0197Y0197R090 S1      
317m0317            VIA   -    MD0080PA00X+026434Y+003530X0180Y0180     S3      
327m0317            GF1   -B20        A01X+026240Y+001378X0280Y1650     S1      
317m0318            VIA   -    MD0080PA00X+039113Y+015875X0180Y0180     S0      
327m0318            U24   -B8         A01X+039310Y+016072X0197Y0197R090 S1      
317m0318            VIA   -    MD0080PA00X+029584Y+004810X0180Y0180     S3      
327m0318            GF1   -B14        A01X+023878Y+001378X0280Y1650     S1      
317m0319            VIA   -    MD0080PA00X+029584Y+004490X0180Y0180     S3      
317m0319            VIA   -    MD0080PA00X+038719Y+015875X0180Y0180     S0      
327m0319            U24   -A8         A01X+038916Y+016072X0197Y0197R090 S1      
327m0319            GF1   -B15        A01X+024272Y+001378X0280Y1650     S1      
317m0320            VIA   -    MD0080PA00X+031250Y+008750X0180Y0180R045 S3      
327m0320            C35   -2          A10X+029730Y+006260X0280Y0240R270 S2      
317m0320            VIA   -    MD0080PA00X+039900Y+015482X0180Y0180     S0      
327m0320            U24   -D7         A01X+040097Y+015678X0197Y0197R090 S1      
317m0321            VIA   -    MD0080PA00X+031476Y+008524X0180Y0180R045 S3      
327m0321            C36   -2          A10X+030230Y+006260X0280Y0240R270 S2      
317m0321            VIA   -    MD0080PA00X+039507Y+015482X0180Y0180     S0      
327m0321            U24   -C7         A01X+039704Y+015678X0197Y0197R090 S1      
317m0322            VIA   -    MD0080PA00X+028186Y+007630X0180Y0180R090 S3      
327m0322            C28   -2          A10X+028006Y+006260X0280Y0240R270 S2      
317m0322            VIA   -    MD0080PA00X+039113Y+015088X0180Y0180     S0      
327m0322            U24   -B6         A01X+039310Y+015285X0197Y0197R090 S1      
317m0323            VIA   -    MD0080PA00X+028506Y+007630X0180Y0180R090 S3      
327m0323            C34   -2          A10X+028506Y+006260X0280Y0240R270 S2      
317m0323            VIA   -    MD0080PA00X+038719Y+015088X0180Y0180     S0      
327m0323            U24   -A6         A01X+038916Y+015285X0197Y0197R090 S1      
317m0324            VIA   -    MD0080PA00X+026671Y+007630X0180Y0180R090 S3      
327m0324            C26   -2          A10X+026581Y+006260X0280Y0240R270 S2      
317m0324            VIA   -    MD0080PA00X+039900Y+014694X0180Y0180     S0      
327m0324            U24   -D5         A01X+040097Y+014891X0197Y0197R090 S1      
317m0325            VIA   -    MD0080PA00X+026991Y+007630X0180Y0180R090 S3      
327m0325            C27   -2          A10X+027081Y+006260X0280Y0240R270 S2      
317m0325            VIA   -    MD0080PA00X+039507Y+014694X0180Y0180     S0      
327m0325            U24   -C5         A01X+039704Y+014891X0197Y0197R090 S1      
317m0326            VIA   -    MD0080PA00X+024702Y+007630X0180Y0180R090 S3      
327m0326            C24   -2          A10X+024612Y+006260X0280Y0240R270 S2      
317m0326            VIA   -    MD0080PA00X+039113Y+014300X0180Y0180     S0      
327m0326            U24   -B4         A01X+039310Y+014497X0197Y0197R090 S1      
317m0327            VIA   -    MD0080PA00X+025022Y+007630X0180Y0180R090 S3      
327m0327            C25   -2          A10X+025112Y+006260X0280Y0240R270 S2      
317m0327            VIA   -    MD0080PA00X+038719Y+014300X0180Y0180     S0      
327m0327            U24   -A4         A01X+038916Y+014497X0197Y0197R090 S1      
317CARD_PRESENT     VIA   -    MD0100PA00X+018890Y+005496X0200Y0200     S3      
327CARD_PRESENT     R22   -1          A01X+025112Y+006260X0280Y0240R270 S1      
317CARD_PRESENT     VIA   -    MD0080PA00X+024350Y+004865X0180Y0180     S3      
327CARD_PRESENT     R23   -1   M      A10X+018646Y+006022X0280Y0240R270 S2      
327CARD_PRESENT     GF1   -A1         A10X+017972Y+001573X0280Y1260     S2      
317BNO080_I2C_SDA   VIA   -    MD0100PA00X+035600Y+030230X0200Y0200     S3      
327BNO080_I2C_SDA   R74   -2   M      A10X+034610Y+022550X0280Y0240R180 S2      
327BNO080_I2C_SDA   R76   -1          A10X+034610Y+022100X0280Y0240     S2      
327BNO080_I2C_SDA   U4    -11         A01X+030425Y+033534X0140Y0620R270 S1      
317BNO080_I2C_SCL   VIA   -    MD0100PA00X+035700Y+029550X0200Y0200     S3      
327BNO080_I2C_SCL   R77   -1   M      A10X+033290Y+022100X0280Y0240R180 S2      
327BNO080_I2C_SCL   R75   -2          A10X+033290Y+022550X0280Y0240     S2      
327BNO080_I2C_SCL   U4    -12         A01X+030425Y+033278X0140Y0620R270 S1      
327m0328            U3    -4          A01X+028480Y+005794X0130Y0380R090 S1      
327m0328            R57   -1   M      A01X+029540Y+005744X0280Y0240     S1      
317m0328            VIA   -    MD0100PA00X+049750Y+021400X0200Y0200     S3      
327m0328            R356  -1          A01X+049260Y+020700X0280Y0240R180 S1      
317m0328            VIA   -    MD0100PA00X+050300Y+009949X0200Y0200     S3      
C                                                                               
C  ****************************************                                     
C      DUMMY NET PINS & VIAS ON THE BOARD                                       
C  ****************************************                                     
C                                                                               
317_d_14bf4508      VIA   -     D0080PA00X+045018Y+015088X0180Y0180     S0      
327_d_14bf4508      U24   -T6         A01X+044822Y+015285X0197Y0197R090 S1      
327_d_1461f868      U24   -Y17        A01X+046396Y+019615X0197Y0197R090 S1      
317_d_1461f868      VIA   -     D0080PA00X+046593Y+019812X0180Y0180     S0      
317_d_145015f8      VIA   -     D0080PA00X+040688Y+019025X0180Y0180     S0      
327_d_145015f8      U24   -F15        A01X+040885Y+018828X0197Y0197R090 S1      
327_d_1460bd58      U24   -T3         A01X+044822Y+014104X0197Y0197R090 S1      
317_d_1460bd58      VIA   -     D0080PA00X+045018Y+013907X0180Y0180     S0      
317_d_14500bd0      VIA   -     D0080PA00X+040688Y+021387X0180Y0180     S0      
327_d_14500bd0      U24   -F21        A01X+040885Y+021190X0197Y0197R090 S1      
317_d_14500d38      VIA   -     D0080PA00X+042263Y+020600X0180Y0180     S0      
327_d_14500d38      U24   -K19        A01X+042460Y+020403X0197Y0197R090 S1      
327_d_14501648      U24   -C19        A01X+039704Y+020403X0197Y0197R090 S1      
317_d_14501648      VIA   -     D0080PA00X+039507Y+020600X0180Y0180     S0      
317_d_14500ce8      VIA   -     D0080PA00X+042263Y+020206X0180Y0180     S0      
327_d_14500ce8      U24   -K18        A01X+042460Y+020009X0197Y0197R090 S1      
327_d_1461cb70      U24   -L20        A01X+042853Y+020796X0197Y0197R090 S1      
317_d_1461cb70      VIA   -     D0080PA00X+042656Y+020993X0180Y0180     S0      
327_d_144fdc60      U24   -L19        A01X+042853Y+020403X0197Y0197R090 S1      
317_d_144fdc60      VIA   -     D0080PA00X+042656Y+020600X0180Y0180     S0      
317_d_14607d40      VIA   -     D0080PA00X+045018Y+019025X0180Y0180     S0      
327_d_14607d40      U24   -T15        A01X+044822Y+018828X0197Y0197R090 S1      
317_d_14501aa8      VIA   -     D0080PA00X+047381Y+020993X0180Y0180     S0      
327_d_14501aa8      U24   -AB20       A01X+047184Y+020796X0197Y0197R090 S1      
317_d_14500d88      VIA   -     D0080PA00X+040294Y+020206X0180Y0180     S0      
327_d_14500d88      U24   -E18        A01X+040491Y+020009X0197Y0197R090 S1      
327_d_145014b8      U24   -T14        A01X+044822Y+018434X0197Y0197R090 S1      
317_d_145014b8      VIA   -     D0080PA00X+045018Y+018631X0180Y0180     S0      
317_d_14501af8      VIA   -     D0080PA00X+046987Y+020600X0180Y0180     S0      
327_d_14501af8      U24   -AA19       A01X+046790Y+020403X0197Y0197R090 S1      
327_d_14612bb8      U24   -W16        A01X+046003Y+019222X0197Y0197R090 S1      
317_d_14612bb8      VIA   -     D0080PA00X+046200Y+019418X0180Y0180     S0      
327_d_14621268      U24   -W17        A01X+046003Y+019615X0197Y0197R090 S1      
317_d_14621268      VIA   -     D0080PA00X+046200Y+019812X0180Y0180     S0      
317_d_14500d10      VIA   -     D0080PA00X+042656Y+020206X0180Y0180     S0      
327_d_14500d10      U24   -L18        A01X+042853Y+020009X0197Y0197R090 S1      
327_d_1460d3d0      U24   -W15        A01X+046003Y+018828X0197Y0197R090 S1      
317_d_1460d3d0      VIA   -     D0080PA00X+046200Y+019025X0180Y0180     S0      
327_d_146106e0      U24   -V17        A01X+045609Y+019615X0197Y0197R090 S1      
317_d_146106e0      VIA   -     D0080PA00X+045806Y+019812X0180Y0180     S0      
317_d_14500ae0      VIA   -     D0080PA00X+045412Y+020206X0180Y0180     S0      
327_d_14500ae0      U24   -U18        A01X+045215Y+020009X0197Y0197R090 S1      
317_d_14500d60      VIA   -     D0080PA00X+043444Y+020993X0180Y0180     S0      
327_d_14500d60      U24   -M20        A01X+043247Y+020796X0197Y0197R090 S1      
327_d_145016c0      U24   -F20        A01X+040885Y+020796X0197Y0197R090 S1      
317_d_145016c0      VIA   -     D0080PA00X+040688Y+020993X0180Y0180     S2      
317_d_14500810      VIA   -     D0080PA00X+046987Y+015088X0180Y0180     S0      
327_d_14500810      U24   -AA6        A01X+046790Y+015285X0197Y0197R090 S1      
317_d_14500a90      VIA   -     D0080PA00X+045412Y+019812X0180Y0180     S0      
327_d_14500a90      U24   -U17        A01X+045215Y+019615X0197Y0197R090 S1      
327_d_145016e8      U24   -F19        A01X+040885Y+020403X0197Y0197R090 S1      
317_d_145016e8      VIA   -     D0080PA00X+040688Y+020600X0180Y0180     S0      
317_d_14500ef0      VIA   -     D0080PA00X+046593Y+015088X0180Y0180     S0      
327_d_14500ef0      U24   -Y6         A01X+046396Y+015285X0197Y0197R090 S1      
327_d_145a8528      U24   -C20        A01X+039704Y+020796X0197Y0197R090 S1      
317_d_145a8528      VIA   -     D0080PA00X+039507Y+020993X0180Y0180     S0      
327_d_145f4618      U24   -W7         A01X+046003Y+015678X0197Y0197R090 S1      
317_d_145f4618      VIA   -     D0080PA00X+046200Y+015482X0180Y0180     S0      
327_d_145a2a50      U24   -D20        A01X+040097Y+020796X0197Y0197R090 S1      
317_d_145a2a50      VIA   -     D0080PA00X+039900Y+020993X0180Y0180     S2      
327_d_145019b8      U24   -V7         A01X+045609Y+015678X0197Y0197R090 S1      
317_d_145019b8      VIA   -     D0080PA00X+045806Y+015482X0180Y0180     S0      
317_d_14501ad0      VIA   -     D0080PA00X+046987Y+019418X0180Y0180     S0      
327_d_14501ad0      U24   -AA16       A01X+046790Y+019222X0197Y0197R090 S1      
317_d_14500b08      VIA   -     D0080PA00X+045018Y+020206X0180Y0180     S0      
327_d_14500b08      U24   -T18        A01X+044822Y+020009X0197Y0197R090 S1      
317_d_14500680      VIA   -     D0080PA00X+044625Y+020206X0180Y0180     S0      
327_d_14500680      U24   -R18        A01X+044428Y+020009X0197Y0197R090 S1      
317_d_14500ab8      VIA   -     D0080PA00X+044231Y+019812X0180Y0180     S0      
327_d_14500ab8      U24   -P17        A01X+044034Y+019615X0197Y0197R090 S1      
327_d_1461f840      U24   -R16        A01X+044428Y+019222X0197Y0197R090 S1      
317_d_1461f840      VIA   -     D0080PA00X+044625Y+019418X0180Y0180     S0      
317_d_14500b80      VIA   -     D0080PA00X+043837Y+018631X0180Y0180     S0      
327_d_14500b80      U24   -N14        A01X+043641Y+018434X0197Y0197R090 S1      
317_d_14500b58      VIA   -     D0080PA00X+043837Y+018237X0180Y0180     S0      
327_d_14500b58      U24   -N13        A01X+043641Y+018041X0197Y0197R090 S1      
317_d_14500a68      VIA   -     D0080PA00X+044625Y+019812X0180Y0180     S0      
327_d_14500a68      U24   -R17        A01X+044428Y+019615X0197Y0197R090 S1      
327_d_14501710      U24   -G16        A01X+041278Y+019222X0197Y0197R090 S1      
317_d_14501710      VIA   -     D0080PA00X+041082Y+019418X0180Y0180     S0      
327_d_146087f0      U24   -E17        A01X+040491Y+019615X0197Y0197R090 S1      
317_d_146087f0      VIA   -     D0080PA00X+040294Y+019812X0180Y0180     S0      
317_d_145009a0      VIA   -     D0080PA00X+045806Y+021781X0180Y0180     S0      
327_d_145009a0      U24   -V22        A01X+045609Y+021584X0197Y0197R090 S1      
317_d_14501350      VIA   -     D0080PA00X+047381Y+019025X0180Y0180     S0      
327_d_14501350      U24   -AB15       A01X+047184Y+018828X0197Y0197R090 S1      
317_d_14500a18      VIA   -     D0080PA00X+045412Y+021387X0180Y0180     S0      
327_d_14500a18      U24   -U21        A01X+045215Y+021190X0197Y0197R090 S1      
327_d_14501760      U24   -G18        A01X+041278Y+020009X0197Y0197R090 S1      
317_d_14501760      VIA   -     D0080PA00X+041082Y+020206X0180Y0180     S0      
317_d_14500a40      VIA   -     D0080PA00X+045018Y+021387X0180Y0180     S0      
327_d_14500a40      U24   -T21        A01X+044822Y+021190X0197Y0197R090 S1      
327_d_145017b0      U24   -D16        A01X+040097Y+019222X0197Y0197R090 S1      
317_d_145017b0      VIA   -     D0080PA00X+039900Y+019418X0180Y0180     S0      
327_d_145017d8      U24   -E16        A01X+040491Y+019222X0197Y0197R090 S1      
317_d_145017d8      VIA   -     D0080PA00X+040294Y+019418X0180Y0180     S0      
327_d_14501508      U24   -T20        A01X+044822Y+020796X0197Y0197R090 S1      
317_d_14501508      VIA   -     D0080PA00X+045018Y+020993X0180Y0180     S0      
327_d_14501800      U24   -H18        A01X+041672Y+020009X0197Y0197R090 S1      
317_d_14501800      VIA   -     D0080PA00X+041475Y+020206X0180Y0180     S0      
317_d_145009f0      VIA   -     D0080PA00X+046200Y+021781X0180Y0180     S0      
327_d_145009f0      U24   -W22        A01X+046003Y+021584X0197Y0197R090 S1      
317_d_14500ba8      VIA   -     D0080PA00X+040294Y+018631X0180Y0180     S0      
327_d_14500ba8      U24   -E14        A01X+040491Y+018434X0197Y0197R090 S1      
317_d_1460c110      VIA   -     D0080PA00X+040688Y+014300X0180Y0180     S0      
327_d_1460c110      U24   -F4         A01X+040885Y+014497X0197Y0197R090 S1      
317_d_145008d8      VIA   -     D0080PA00X+045412Y+015482X0180Y0180     S0      
327_d_145008d8      U24   -U7         A01X+045215Y+015678X0197Y0197R090 S1      
317_d_14500fb8      VIA   -     D0080PA00X+042656Y+015088X0180Y0180     S0      
327_d_14500fb8      U24   -L6         A01X+042853Y+015285X0197Y0197R090 S1      
327_d_146167c8      U24   -J16        A01X+042066Y+019222X0197Y0197R090 S1      
317_d_146167c8      VIA   -     D0080PA00X+041869Y+019418X0180Y0180     S0      
317_d_1438ee30      VIA   -     D0080PA00X+041475Y+014694X0180Y0180     S0      
327_d_1438ee30      U24   -H5         A01X+041672Y+014891X0197Y0197R090 S1      
327_d_14606b78      U24   -J5         A01X+042066Y+014891X0197Y0197R090 S1      
317_d_14606b78      VIA   -     D0080PA00X+041869Y+014694X0180Y0180     S0      
317_d_14500c20      VIA   -     D0080PA00X+041869Y+021387X0180Y0180     S0      
327_d_14500c20      U24   -J21        A01X+042066Y+021190X0197Y0197R090 S1      
317_d_14500838      VIA   -     D0080PA00X+046987Y+014300X0180Y0180     S0      
327_d_14500838      U24   -AA4        A01X+046790Y+014497X0197Y0197R090 S1      
317_d_14501008      VIA   -     D0080PA00X+041082Y+013907X0180Y0180     S0      
327_d_14501008      U24   -G3         A01X+041278Y+014104X0197Y0197R090 S1      
317_d_145006f8      VIA   -     D0080PA00X+046593Y+014300X0180Y0180     S0      
327_d_145006f8      U24   -Y4         A01X+046396Y+014497X0197Y0197R090 S1      
317_d_14500f90      VIA   -     D0080PA00X+041475Y+013907X0180Y0180     S0      
327_d_14500f90      U24   -H3         A01X+041672Y+014104X0197Y0197R090 S1      
327_d_14501d78      U24   -W4         A01X+046003Y+014497X0197Y0197R090 S1      
317_d_14501d78      VIA   -     D0080PA00X+046200Y+014300X0180Y0180     S0      
317_d_14500fe0      VIA   -     D0080PA00X+041082Y+014300X0180Y0180     S0      
327_d_14500fe0      U24   -G4         A01X+041278Y+014497X0197Y0197R090 S1      
327_d_145aab28      U24   -V4         A01X+045609Y+014497X0197Y0197R090 S1      
317_d_145aab28      VIA   -     D0080PA00X+045806Y+014300X0180Y0180     S0      
317_d_14500f68      VIA   -     D0080PA00X+041475Y+014300X0180Y0180     S0      
327_d_14500f68      U24   -H4         A01X+041672Y+014497X0197Y0197R090 S1      
327_d_145f2028      U24   -J4         A01X+042066Y+014497X0197Y0197R090 S1      
317_d_145f2028      VIA   -     D0080PA00X+041869Y+014300X0180Y0180     S0      
327_d_145ffcc8      U24   -K4         A01X+042460Y+014497X0197Y0197R090 S1      
317_d_145ffcc8      VIA   -     D0080PA00X+042263Y+014300X0180Y0180     S0      
317_d_14500e78      VIA   -     D0080PA00X+045412Y+014694X0180Y0180     S0      
327_d_14500e78      U24   -U5         A01X+045215Y+014891X0197Y0197R090 S1      
327_d_146169b0      U24   -K3         A01X+042460Y+014104X0197Y0197R090 S1      
317_d_146169b0      VIA   -     D0080PA00X+042263Y+013907X0180Y0180     S0      
317_d_14500ea0      VIA   -     D0080PA00X+045018Y+014694X0180Y0180     S0      
327_d_14500ea0      U24   -T5         A01X+044822Y+014891X0197Y0197R090 S1      
327_d_146020e8      U24   -L3         A01X+042853Y+014104X0197Y0197R090 S1      
317_d_146020e8      VIA   -     D0080PA00X+042656Y+013907X0180Y0180     S0      
317_d_14501148      VIA   -     D0080PA00X+046200Y+014694X0180Y0180     S0      
327_d_14501148      U24   -W5         A01X+046003Y+014891X0197Y0197R090 S1      
317_d_14501918      VIA   -     D0080PA00X+042656Y+013119X0180Y0180     S0      
327_d_14501918      U24   -L1         A01X+042853Y+013316X0197Y0197R090 S1      
327_d_14604c18      U24   -W6         A01X+046003Y+015285X0197Y0197R090 S1      
317_d_14604c18      VIA   -     D0080PA00X+046200Y+015088X0180Y0180     S0      
317_d_14501940      VIA   -     D0080PA00X+043444Y+013119X0180Y0180     S0      
327_d_14501940      U24   -M1         A01X+043247Y+013316X0197Y0197R090 S1      
317_d_14500888      VIA   -     D0080PA00X+045806Y+014694X0180Y0180     S0      
327_d_14500888      U24   -V5         A01X+045609Y+014891X0197Y0197R090 S1      
317_d_14501968      VIA   -     D0080PA00X+043444Y+013513X0180Y0180     S0      
327_d_14501968      U24   -M2         A01X+043247Y+013710X0197Y0197R090 S1      
317_d_145008b0      VIA   -     D0080PA00X+045412Y+015088X0180Y0180     S0      
327_d_145008b0      U24   -U6         A01X+045215Y+015285X0197Y0197R090 S1      
317_d_14601dd8      VIA   -     D0080PA00X+043444Y+013907X0180Y0180     S0      
327_d_14601dd8      U24   -M3         A01X+043247Y+014104X0197Y0197R090 S1      
327_d_14501878      U24   -J6         A01X+042066Y+015285X0197Y0197R090 S1      
317_d_14501878      VIA   -     D0080PA00X+041869Y+015088X0180Y0180     S0      
317_d_14500ec8      VIA   -     D0080PA00X+044625Y+015088X0180Y0180     S0      
327_d_14500ec8      U24   -R6         A01X+044428Y+015285X0197Y0197R090 S1      
327_d_144fb060      U24   -K6         A01X+042460Y+015285X0197Y0197R090 S1      
317_d_144fb060      VIA   -     D0080PA00X+042263Y+015088X0180Y0180     S0      
327_d_145ffcf0      U24   -L4         A01X+042853Y+014497X0197Y0197R090 S1      
317_d_145ffcf0      VIA   -     D0080PA00X+042656Y+014300X0180Y0180     S2      
327_d_144fee38      U24   -L5         A01X+042853Y+014891X0197Y0197R090 S1      
317_d_144fee38      VIA   -     D0080PA00X+042656Y+014694X0180Y0180     S0      
327_d_146134d0      U24   -N3         A01X+043641Y+014104X0197Y0197R090 S1      
317_d_146134d0      VIA   -     D0080PA00X+043837Y+013907X0180Y0180     S0      
327_d_14501670      U24   -N4         A01X+043641Y+014497X0197Y0197R090 S1      
317_d_14501670      VIA   -     D0080PA00X+043837Y+014300X0180Y0180     S0      
317_d_14501698      VIA   -     D0080PA00X+045412Y+013119X0180Y0180     S0      
327_d_14501698      U24   -U1         A01X+045215Y+013316X0197Y0197R090 S1      
317_d_1460da60      VIA   -     D0080PA00X+044988Y+013150X0180Y0180     S0      
327_d_1460da60      U24   -T1         A01X+044822Y+013316X0197Y0197R090 S1      
317_d_14500cc0      VIA   -     D0080PA00X+043444Y+019812X0180Y0180     S0      
327_d_14500cc0      U24   -M17        A01X+043247Y+019615X0197Y0197R090 S1      
317_d_14501a58      VIA   -     D0080PA00X+045784Y+013534X0180Y0180     S0      
327_d_14501a58      U24   -V2         A01X+045609Y+013710X0197Y0197R090 S1      
317_d_145011c0      VIA   -     D0080PA00X+039113Y+013513X0180Y0180     S0      
327_d_145011c0      U24   -B2         A01X+039310Y+013710X0197Y0197R090 S1      
317_d_14c04520      VIA   -     D0080PA00X+045412Y+013513X0180Y0180     S0      
327_d_14c04520      U24   -U2         A01X+045215Y+013710X0197Y0197R090 S1      
317_d_14500e50      VIA   -     D0080PA00X+039507Y+013513X0180Y0180     S0      
327_d_14500e50      U24   -C2         A01X+039704Y+013710X0197Y0197R090 S1      
317_d_1460c738      VIA   -     D0080PA00X+044594Y+013544X0180Y0180     S0      
327_d_1460c738      U24   -R2         A01X+044428Y+013710X0197Y0197R090 S1      
317_d_1460e390      VIA   -     D0080PA00X+039900Y+013119X0180Y0180     S0      
327_d_1460e390      U24   -D1         A01X+040097Y+013316X0197Y0197R090 S1      
327_d_145fa5b0      U24   -R3         A01X+044428Y+014104X0197Y0197R090 S1      
317_d_145fa5b0      VIA   -     D0080PA00X+044625Y+013907X0180Y0180     S0      
317_d_14500720      VIA   -     D0080PA00X+046593Y+013513X0180Y0180     S0      
327_d_14500720      U24   -Y2         A01X+046396Y+013710X0197Y0197R090 S1      
317_d_14601c78      VIA   -     D0080PA00X+039900Y+013512X0180Y0180     S0      
327_d_14601c78      U24   -D2         A01X+040097Y+013710X0197Y0197R090 S1      
317_d_14500748      VIA   -     D0080PA00X+046200Y+013513X0180Y0180     S0      
327_d_14500748      U24   -W2         A01X+046003Y+013710X0197Y0197R090 S1      
317_d_145013a0      VIA   -     D0080PA00X+046987Y+018631X0180Y0180     S0      
327_d_145013a0      U24   -AA14       A01X+046790Y+018434X0197Y0197R090 S1      
327_d_145014e0      U24   -R19        A01X+044428Y+020403X0197Y0197R090 S1      
317_d_145014e0      VIA   -     D0080PA00X+044625Y+020600X0180Y0180     S0      
317_d_145010f8      VIA   -     D0080PA00X+040687Y+013119X0180Y0180     S0      
327_d_145010f8      U24   -F1         A01X+040885Y+013316X0197Y0197R090 S1      
327_d_1460d208      U24   -Y13        A01X+046396Y+018041X0197Y0197R090 S1      
317_d_1460d208      VIA   -     D0080PA00X+046593Y+018237X0180Y0180     S0      
327_d_145aa768      U24   -P19        A01X+044034Y+020403X0197Y0197R090 S1      
317_d_145aa768      VIA   -     D0080PA00X+044231Y+020600X0180Y0180     S0      
317_d_145013f0      VIA   -     D0080PA00X+041081Y+013119X0180Y0180     S0      
327_d_145013f0      U24   -G1         A01X+041278Y+013316X0197Y0197R090 S1      
327_d_1460b820      U24   -V3         A01X+045609Y+014104X0197Y0197R090 S1      
317_d_1460b820      VIA   -     D0080PA00X+045806Y+013907X0180Y0180     S0      
317_d_14603918      VIA   -     D0080PA00X+040294Y+013907X0180Y0180     S0      
327_d_14603918      U24   -E3         A01X+040491Y+014104X0197Y0197R090 S1      
327_d_145a1480      U24   -U3         A01X+045215Y+014104X0197Y0197R090 S1      
317_d_145a1480      VIA   -     D0080PA00X+045412Y+013907X0180Y0180     S0      
317_d_143fc310      VIA   -     D0080PA00X+040688Y+013907X0180Y0180     S0      
327_d_143fc310      U24   -F3         A01X+040885Y+014104X0197Y0197R090 S1      
317_d_14501df0      VIA   -     D0080PA00X+047381Y+017844X0180Y0180     S0      
327_d_14501df0      U24   -AB12       A01X+047184Y+017647X0197Y0197R090 S1      
317_d_14500770      VIA   -     D0080PA00X+047381Y+013119X0180Y0180     S0      
327_d_14500770      U24   -AB1        A01X+047184Y+013316X0197Y0197R090 S1      
317_d_14501120      VIA   -     D0080PA00X+041869Y+013119X0180Y0180     S0      
327_d_14501120      U24   -J1         A01X+042066Y+013316X0197Y0197R090 S1      
317_d_14501da0      VIA   -     D0080PA00X+047381Y+017056X0180Y0180     S0      
327_d_14501da0      U24   -AB11       A01X+047184Y+017253X0197Y0197R090 S1      
317_d_14500798      VIA   -     D0080PA00X+046987Y+013119X0180Y0180     S0      
327_d_14500798      U24   -AA1        A01X+046790Y+013316X0197Y0197R090 S1      
317_d_145010a8      VIA   -     D0080PA00X+042263Y+013119X0180Y0180     S0      
327_d_145010a8      U24   -K1         A01X+042460Y+013316X0197Y0197R090 S1      
317_d_14501170      VIA   -     D0080PA00X+041082Y+013513X0180Y0180     S0      
327_d_14501170      U24   -G2         A01X+041278Y+013710X0197Y0197R090 S1      
317_d_14501080      VIA   -     D0080PA00X+041475Y+013513X0180Y0180     S0      
327_d_14501080      U24   -H2         A01X+041672Y+013710X0197Y0197R090 S1      
317_d_14500860      VIA   -     D0080PA00X+046987Y+013907X0180Y0180     S0      
327_d_14500860      U24   -AA3        A01X+046790Y+014104X0197Y0197R090 S1      
317_d_14501030      VIA   -     D0080PA00X+041869Y+013513X0180Y0180     S0      
327_d_14501030      U24   -J2         A01X+042066Y+013710X0197Y0197R090 S1      
317_d_145007c0      VIA   -     D0080PA00X+046593Y+013907X0180Y0180     S0      
327_d_145007c0      U24   -Y3         A01X+046396Y+014104X0197Y0197R090 S1      
317_d_14501058      VIA   -     D0080PA00X+042263Y+013513X0180Y0180     S0      
327_d_14501058      U24   -K2         A01X+042460Y+013710X0197Y0197R090 S1      
317_d_14501418      VIA   -     D0080PA00X+047381Y+021781X0180Y0180     S0      
327_d_14501418      U24   -AB22       A01X+047184Y+021584X0197Y0197R090 S1      
317_d_14501580      VIA   -     D0080PA00X+047381Y+021387X0180Y0180     S0      
327_d_14501580      U24   -AB21       A01X+047184Y+021190X0197Y0197R090 S1      
327_d_14501440      U24   -V20        A01X+045609Y+020796X0197Y0197R090 S1      
317_d_14501440      VIA   -     D0080PA00X+045806Y+020993X0180Y0180     S0      
327_d_14501468      U24   -U20        A01X+045215Y+020796X0197Y0197R090 S1      
317_d_14501468      VIA   -     D0080PA00X+045412Y+020993X0180Y0180     S0      
317_d_14500928      VIA   -     D0080PA00X+045806Y+018631X0180Y0180     S0      
327_d_14500928      U24   -V14        A01X+045609Y+018434X0197Y0197R090 S1      
317_d_145001a8      VIA   -     D0080PA00X+046593Y+020600X0180Y0180     S0      
327_d_145001a8      U24   -Y19        A01X+046396Y+020403X0197Y0197R090 S1      
317_d_145006d0      VIA   -     D0080PA00X+045806Y+020600X0180Y0180     S0      
327_d_145006d0      U24   -V19        A01X+045609Y+020403X0197Y0197R090 S1      
317_d_14500900      VIA   -     D0080PA00X+045412Y+019025X0180Y0180     S0      
327_d_14500900      U24   -U15        A01X+045215Y+018828X0197Y0197R090 S1      
317_d_14500b30      VIA   -     D0080PA00X+045806Y+020206X0180Y0180     S0      
327_d_14500b30      U24   -V18        A01X+045609Y+020009X0197Y0197R090 S1      
317_d_14500c98      VIA   -     D0080PA00X+042263Y+019812X0180Y0180     S0      
327_d_14500c98      U24   -K17        A01X+042460Y+019615X0197Y0197R090 S1      
317_d_14500c70      VIA   -     D0080PA00X+042656Y+019418X0180Y0180     S0      
327_d_14500c70      U24   -L16        A01X+042853Y+019222X0197Y0197R090 S1      
327_d_14501788      U24   -G17        A01X+041278Y+019615X0197Y0197R090 S1      
317_d_14501788      VIA   -     D0080PA00X+041082Y+019812X0180Y0180     S0      
327_d_14603bf8      U24   -H17        A01X+041672Y+019615X0197Y0197R090 S1      
317_d_14603bf8      VIA   -     D0080PA00X+041475Y+019812X0180Y0180     S0      
317_d_145009c8      VIA   -     D0080PA00X+046200Y+021387X0180Y0180     S0      
327_d_145009c8      U24   -W21        A01X+046003Y+021190X0197Y0197R090 S1      
317_d_14501dc8      VIA   -     D0080PA00X+046987Y+017056X0180Y0180     S0      
327_d_14501dc8      U24   -AA11       A01X+046790Y+017253X0197Y0197R090 S1      
317_d_14662d68      VIA   -     D0080PA00X+046987Y+016663X0180Y0180     S0      
327_d_14662d68      U24   -AA10       A01X+046790Y+016860X0197Y0197R090 S1      
327N/C              U24   -B18        A01X+039310Y+020009X0197Y0197R090 S1      
327N/C              U24   -B17        A01X+039310Y+019615X0197Y0197R090 S1      
327N/C              U24   -A19        A01X+038916Y+020403X0197Y0197R090 S1      
327N/C              U24   -B16        A01X+039310Y+019222X0197Y0197R090 S1      
327N/C              U24   -B15        A01X+039310Y+018828X0197Y0197R090 S1      
327N/C              U24   -Y22        A01X+046396Y+021584X0197Y0197R090 S1      
327N/C              U24   -A16        A01X+038916Y+019222X0197Y0197R090 S1      
327N/C              U24   -Y21        A01X+046396Y+021190X0197Y0197R090 S1      
327N/C              U24   -A15        A01X+038916Y+018828X0197Y0197R090 S1      
327N/C              U24   -A1         A01X+038916Y+013316X0197Y0197R090 S1      
327N/C              U24   -B1         A01X+039310Y+013316X0197Y0197R090 S1      
327N/C              U24   -E1         A01X+040491Y+013316X0197Y0197R090 S1      
327N/C              U24   -E2         A01X+040491Y+013710X0197Y0197R090 S1      
327N/C              U31   -7          A10X+017485Y+034880X0200Y0650R270 S2      
327N/C              CR5   -4          A01X+001975Y+010435X0570Y0390R090 S1      
327N/C              CR4   -4          A01X+001975Y+021835X0570Y0390R090 S1      
327N/C              CR6   -4          A10X+057455Y+030095X0570Y0390R270 S2      
327N/C              CR7   -4          A10X+057505Y+027245X0570Y0390R270 S2      
327N/C              J14   -6          A01X+055054Y+028210X0500Y1400R090 S1      
327N/C              J14   -7          A01X+057106Y+029210X0500Y1400R090 S1      
327N/C              J14   -8          A01X+055054Y+029210X0500Y1400R090 S1      
327N/C              U2    -5          A01X+016622Y+007400X0200Y0650R270 S1      
327N/C              J11   -4          A01X+064105Y+021358X0160Y0530R090 S1      
327N/C              GF1   -B11        A01X+021909Y+001378X0280Y1650     S1      
327N/C              GF1   -A32        A10X+030964Y+001378X0280Y1650     S2      
327N/C              GF1   -B30        A01X+030177Y+001378X0280Y1650     S1      
327N/C              GF1   -A19        A10X+025846Y+001378X0280Y1650     S2      
327N/C              GF1   -B12        A01X+023090Y+001378X0280Y1650     S1      
327N/C              GF1   -B9         A01X+021122Y+001378X0280Y1650     S1      
327N/C              U17   -3          A01X+007574Y+033935X0200Y0470R180 S1      
327N/C              U17   -1          A01X+006826Y+033935X0200Y0470R180 S1      
327N/C              U9    -3          A01X+062325Y+023148X0200Y0470     S1      
327N/C              U9    -1          A01X+063073Y+023148X0200Y0470     S1      
327N/C              U11   -7          A01X+035519Y+019456X0530Y0080R090 S1      
327N/C              U11   -8          A01X+035361Y+019456X0530Y0080R090 S1      
327N/C              U3    -1          A01X+027540Y+006306X0130Y0380R090 S1      
327N/C              Y4    -2          A01X+039800Y+007522X0390Y0550R090 S1      
327N/C              Y3    -2          A01X+043640Y+008237X0350Y0250R090 S1      
327N/C              U25   -8          A01X+056847Y+006790X0410Y0120     S1      
327N/C              U21   -8          A01X+050483Y+027070X0410Y0120R180 S1      
327N/C              U20   -8          A01X+039120Y+030047X0410Y0120R090 S1      
327N/C              P1    -18         A01X+029273Y+017715X0100Y0710R270 S1      
327N/C              P1    -16         A01X+029273Y+017912X0100Y0710R270 S1      
327N/C              P1    -14         A01X+029273Y+018109X0100Y0710R270 S1      
327N/C              P1    -13         A01X+027699Y+018109X0100Y0710R270 S1      
327N/C              P1    -12         A01X+029273Y+018306X0100Y0710R270 S1      
327N/C              P1    -11         A01X+027699Y+018306X0100Y0710R270 S1      
327N/C              P1    -10         A01X+029273Y+018503X0100Y0710R270 S1      
327N/C              U29   -24         A01X+034515Y+023042X0270Y0100     S1      
327N/C              U29   -23         A01X+034515Y+022845X0270Y0100     S1      
327N/C              U29   -22         A01X+034515Y+022648X0270Y0100     S1      
327N/C              U29   -21         A01X+034515Y+022451X0270Y0100     S1      
327N/C              U29   -13         A01X+033285Y+022648X0270Y0100     S1      
327N/C              U29   -12         A01X+033285Y+022845X0270Y0100     S1      
327N/C              U29   -8          A01X+033285Y+023632X0270Y0100     S1      
327N/C              U29   -7          A01X+033285Y+023829X0270Y0100     S1      
327N/C              U29   -1          A01X+034515Y+024026X0270Y0100     S1      
327N/C              U33   -28         A01X+042031Y+038954X0120Y0460R180 S1      
327N/C              U33   -27         A01X+041834Y+038969X0120Y0490R180 S1      
327N/C              U33   -26         A01X+041637Y+038969X0120Y0490R180 S1      
327N/C              U40   -1          A01X+042006Y+034824X0240Y0170R270 S1      
327N/C              U39   -1          A01X+040056Y+034804X0240Y0170R270 S1      
327N/C              U41   -8          A01X+017397Y+030150X0410Y0120     S1      
327N/C              U18   -36         A01X+010344Y+031200X0120Y0640     S1      
327N/C              U18   -60         A01X+013520Y+034179X0120Y0640R090 S1      
327N/C              U18   -59         A01X+013520Y+033982X0120Y0640R090 S1      
327N/C              U18   -58         A01X+013520Y+033785X0120Y0640R090 S1      
327N/C              U18   -57         A01X+013520Y+033588X0120Y0640R090 S1      
327N/C              U18   -55         A01X+013520Y+033195X0120Y0640R090 S1      
327N/C              U18   -54         A01X+013520Y+032998X0120Y0640R090 S1      
327N/C              U18   -53         A01X+013520Y+032801X0120Y0640R090 S1      
327N/C              U18   -46         A01X+012313Y+031200X0120Y0640     S1      
327N/C              U18   -45         A01X+012116Y+031200X0120Y0640     S1      
327N/C              U18   -44         A01X+011919Y+031200X0120Y0640     S1      
327N/C              U18   -43         A01X+011722Y+031200X0120Y0640     S1      
327N/C              U18   -41         A01X+011328Y+031200X0120Y0640     S1      
327N/C              U18   -40         A01X+011132Y+031200X0120Y0640     S1      
C                                                                               
C  ****************************************                                     
C      TOOLING HOLE PINS ON THE BOARD                                           
C  ****************************************                                     
C                                                                               
367                       -     D1000UA00X+026857Y+011214X0900Y0900     S3      
367                       -     D1000UA00X+026857Y+025594X0900Y0900     S3      
367                       -     D1000UA00X+014607Y+026804X0900Y0900     S3      
367                       -     D1000UA00X+014357Y+010604X0900Y0900     S3      
367                       -     D1250UA00X+064004Y+006535X1150Y1150     S3      
367                       -     D1250UA00X+002953Y+037303X1150Y1150     S3      
367                       -     D1250UA00X+002953Y+003681X1150Y1150     S3      
367                       -     D1250UA00X+064004Y+041784X1150Y1150     S3      
367                       -     D1180UA00X+063406Y+033445X1080Y1080R270 S3      
367                       -     D1180UA00X+063406Y+036752X1080Y1080R270 S3      
C                                                                               
C  End-of-Job                                                                   
C                                                                               
999                                                                             
